(kicad_sch (version 20230121) (generator eeschema)

  (paper "A3")

  (title_block
    (title "D1600E PSU Breakout Board")
    (date "2023-10-18")
    (rev "1.4.3")
    (comment 1 "www.antmicro.com")
    (comment 2 "Antmicro Ltd.")
  )

  (junction (at 252.73 54.61) (diameter 0) (color 0 0 0 0)
  )
  (junction (at 44.45 191.77) (diameter 0) (color 0 0 0 0)
  )
  (junction (at 72.39 173.99) (diameter 0) (color 0 0 0 0)
  )
  (junction (at 284.48 36.83) (diameter 0) (color 0 0 0 0)
  )
  (junction (at 312.42 64.77) (diameter 0) (color 0 0 0 0)
  )
  (junction (at 53.34 173.99) (diameter 0) (color 0 0 0 0)
  )
  (junction (at 44.45 173.99) (diameter 0) (color 0 0 0 0)
  )
  (junction (at 229.87 38.1) (diameter 0) (color 0 0 0 0)
  )
  (junction (at 153.67 50.8) (diameter 0) (color 0 0 0 0)
  )
  (junction (at 130.81 36.83) (diameter 0) (color 0 0 0 0)
  )
  (junction (at 104.14 50.8) (diameter 0) (color 0 0 0 0)
  )
  (junction (at 81.28 36.83) (diameter 0) (color 0 0 0 0)
  )
  (junction (at 345.44 72.39) (diameter 0) (color 0 0 0 0)
  )
  (junction (at 72.39 160.02) (diameter 0) (color 0 0 0 0)
  )
  (junction (at 29.21 186.69) (diameter 0) (color 0 0 0 0)
  )
  (junction (at 203.2 50.8) (diameter 0) (color 0 0 0 0)
  )
  (junction (at 153.67 53.34) (diameter 0) (color 0 0 0 0)
  )
  (junction (at 31.75 36.83) (diameter 0) (color 0 0 0 0)
  )
  (junction (at 54.61 53.34) (diameter 0) (color 0 0 0 0)
  )
  (junction (at 252.73 52.07) (diameter 0) (color 0 0 0 0)
  )
  (junction (at 336.55 74.93) (diameter 0) (color 0 0 0 0)
  )
  (junction (at 152.4 104.14) (diameter 0) (color 0 0 0 0)
  )
  (junction (at 54.61 50.8) (diameter 0) (color 0 0 0 0)
  )
  (junction (at 36.83 173.99) (diameter 0) (color 0 0 0 0)
  )
  (junction (at 203.2 53.34) (diameter 0) (color 0 0 0 0)
  )
  (junction (at 36.83 189.23) (diameter 0) (color 0 0 0 0)
  )
  (junction (at 134.62 104.14) (diameter 0) (color 0 0 0 0)
  )
  (junction (at 104.14 53.34) (diameter 0) (color 0 0 0 0)
  )
  (junction (at 180.34 36.83) (diameter 0) (color 0 0 0 0)
  )

  (no_connect (at 92.71 191.77))
  (no_connect (at 154.94 111.76))
  (no_connect (at 92.71 186.69))
  (no_connect (at 287.02 72.39))
  (no_connect (at 287.02 69.85))
  (no_connect (at 92.71 189.23))

  (wire (pts (xy 345.44 82.55) (xy 345.44 85.09))
    (stroke (width 0) (type default))
  )
  (wire (pts (xy 29.21 186.69) (xy 29.21 194.31))
    (stroke (width 0) (type default))
  )
  (wire (pts (xy 182.88 50.8) (xy 179.07 50.8))
    (stroke (width 0) (type default))
  )
  (wire (pts (xy 101.6 48.26) (xy 113.03 48.26))
    (stroke (width 0) (type default))
  )
  (polyline (pts (xy 205.74 160.02) (xy 205.74 167.64))
    (stroke (width 0) (type dash))
  )

  (wire (pts (xy 151.13 50.8) (xy 153.67 50.8))
    (stroke (width 0) (type default))
  )
  (wire (pts (xy 81.28 34.29) (xy 81.28 36.83))
    (stroke (width 0) (type default))
  )
  (wire (pts (xy 187.96 224.79) (xy 190.5 224.79))
    (stroke (width 0) (type default))
  )
  (wire (pts (xy 304.8 74.93) (xy 336.55 74.93))
    (stroke (width 0) (type default))
  )
  (wire (pts (xy 133.35 53.34) (xy 129.54 53.34))
    (stroke (width 0) (type default))
  )
  (wire (pts (xy 166.37 104.14) (xy 152.4 104.14))
    (stroke (width 0) (type default))
  )
  (wire (pts (xy 123.19 203.2) (xy 138.43 203.2))
    (stroke (width 0) (type default))
  )
  (wire (pts (xy 336.55 55.88) (xy 336.55 64.77))
    (stroke (width 0) (type default))
  )
  (polyline (pts (xy 199.39 224.79) (xy 204.47 224.79))
    (stroke (width 0) (type default))
  )
  (polyline (pts (xy 199.39 203.2) (xy 204.47 203.2))
    (stroke (width 0) (type default))
  )

  (wire (pts (xy 219.71 181.61) (xy 222.25 181.61))
    (stroke (width 0) (type default))
  )
  (wire (pts (xy 31.75 36.83) (xy 31.75 48.26))
    (stroke (width 0) (type default))
  )
  (wire (pts (xy 134.62 113.03) (xy 134.62 116.84))
    (stroke (width 0) (type default))
  )
  (wire (pts (xy 92.71 179.07) (xy 99.06 179.07))
    (stroke (width 0) (type default))
  )
  (wire (pts (xy 81.28 48.26) (xy 83.82 48.26))
    (stroke (width 0) (type default))
  )
  (wire (pts (xy 219.71 246.38) (xy 222.25 246.38))
    (stroke (width 0) (type default))
  )
  (wire (pts (xy 360.68 69.85) (xy 374.65 69.85))
    (stroke (width 0) (type default))
  )
  (wire (pts (xy 152.4 109.22) (xy 152.4 104.14))
    (stroke (width 0) (type default))
  )
  (wire (pts (xy 187.96 207.01) (xy 190.5 207.01))
    (stroke (width 0) (type default))
  )
  (wire (pts (xy 284.48 36.83) (xy 284.48 52.07))
    (stroke (width 0) (type default))
  )
  (wire (pts (xy 104.14 53.34) (xy 101.6 53.34))
    (stroke (width 0) (type default))
  )
  (wire (pts (xy 187.96 162.56) (xy 190.5 162.56))
    (stroke (width 0) (type default))
  )
  (wire (pts (xy 187.96 246.38) (xy 190.5 246.38))
    (stroke (width 0) (type default))
  )
  (wire (pts (xy 229.87 49.53) (xy 232.41 49.53))
    (stroke (width 0) (type default))
  )
  (wire (pts (xy 74.93 180.34) (xy 69.85 180.34))
    (stroke (width 0) (type default))
  )
  (wire (pts (xy 53.34 182.88) (xy 74.93 182.88))
    (stroke (width 0) (type default))
  )
  (polyline (pts (xy 205.74 226.06) (xy 205.74 233.68))
    (stroke (width 0) (type dash))
  )

  (wire (pts (xy 154.94 109.22) (xy 152.4 109.22))
    (stroke (width 0) (type default))
  )
  (wire (pts (xy 177.8 255.27) (xy 190.5 255.27))
    (stroke (width 0) (type default))
  )
  (wire (pts (xy 360.68 64.77) (xy 374.65 64.77))
    (stroke (width 0) (type default))
  )
  (wire (pts (xy 44.45 173.99) (xy 53.34 173.99))
    (stroke (width 0) (type default))
  )
  (wire (pts (xy 93.98 161.29) (xy 93.98 160.02))
    (stroke (width 0) (type default))
  )
  (wire (pts (xy 99.06 181.61) (xy 92.71 181.61))
    (stroke (width 0) (type default))
  )
  (wire (pts (xy 83.82 53.34) (xy 80.01 53.34))
    (stroke (width 0) (type default))
  )
  (wire (pts (xy 45.72 36.83) (xy 54.61 36.83))
    (stroke (width 0) (type default))
  )
  (wire (pts (xy 130.81 36.83) (xy 139.7 36.83))
    (stroke (width 0) (type default))
  )
  (wire (pts (xy 250.19 49.53) (xy 261.62 49.53))
    (stroke (width 0) (type default))
  )
  (wire (pts (xy 336.55 82.55) (xy 336.55 85.09))
    (stroke (width 0) (type default))
  )
  (wire (pts (xy 243.84 38.1) (xy 252.73 38.1))
    (stroke (width 0) (type default))
  )
  (wire (pts (xy 44.45 191.77) (xy 74.93 191.77))
    (stroke (width 0) (type default))
  )
  (wire (pts (xy 34.29 53.34) (xy 30.48 53.34))
    (stroke (width 0) (type default))
  )
  (wire (pts (xy 104.14 36.83) (xy 104.14 50.8))
    (stroke (width 0) (type default))
  )
  (wire (pts (xy 99.06 176.53) (xy 92.71 176.53))
    (stroke (width 0) (type default))
  )
  (wire (pts (xy 252.73 38.1) (xy 252.73 52.07))
    (stroke (width 0) (type default))
  )
  (wire (pts (xy 187.96 185.42) (xy 190.5 185.42))
    (stroke (width 0) (type default))
  )
  (wire (pts (xy 29.21 186.69) (xy 74.93 186.69))
    (stroke (width 0) (type default))
  )
  (wire (pts (xy 36.83 173.99) (xy 36.83 176.53))
    (stroke (width 0) (type default))
  )
  (wire (pts (xy 180.34 48.26) (xy 182.88 48.26))
    (stroke (width 0) (type default))
  )
  (wire (pts (xy 54.61 55.88) (xy 54.61 53.34))
    (stroke (width 0) (type default))
  )
  (wire (pts (xy 232.41 52.07) (xy 228.6 52.07))
    (stroke (width 0) (type default))
  )
  (wire (pts (xy 229.87 35.56) (xy 229.87 38.1))
    (stroke (width 0) (type default))
  )
  (wire (pts (xy 53.34 173.99) (xy 72.39 173.99))
    (stroke (width 0) (type default))
  )
  (wire (pts (xy 54.61 36.83) (xy 54.61 50.8))
    (stroke (width 0) (type default))
  )
  (wire (pts (xy 203.2 53.34) (xy 200.66 53.34))
    (stroke (width 0) (type default))
  )
  (wire (pts (xy 153.67 36.83) (xy 153.67 50.8))
    (stroke (width 0) (type default))
  )
  (polyline (pts (xy 207.01 203.2) (xy 212.09 203.2))
    (stroke (width 0) (type default))
  )

  (wire (pts (xy 271.78 62.23) (xy 287.02 62.23))
    (stroke (width 0) (type default))
  )
  (wire (pts (xy 232.41 54.61) (xy 228.6 54.61))
    (stroke (width 0) (type default))
  )
  (wire (pts (xy 52.07 50.8) (xy 54.61 50.8))
    (stroke (width 0) (type default))
  )
  (wire (pts (xy 123.19 198.12) (xy 138.43 198.12))
    (stroke (width 0) (type default))
  )
  (wire (pts (xy 345.44 77.47) (xy 345.44 72.39))
    (stroke (width 0) (type default))
  )
  (wire (pts (xy 312.42 71.12) (xy 312.42 85.09))
    (stroke (width 0) (type default))
  )
  (wire (pts (xy 36.83 189.23) (xy 36.83 194.31))
    (stroke (width 0) (type default))
  )
  (wire (pts (xy 187.96 158.75) (xy 190.5 158.75))
    (stroke (width 0) (type default))
  )
  (wire (pts (xy 134.62 104.14) (xy 134.62 107.95))
    (stroke (width 0) (type default))
  )
  (wire (pts (xy 44.45 181.61) (xy 44.45 191.77))
    (stroke (width 0) (type default))
  )
  (wire (pts (xy 271.78 74.93) (xy 287.02 74.93))
    (stroke (width 0) (type default))
  )
  (wire (pts (xy 72.39 194.31) (xy 72.39 201.93))
    (stroke (width 0) (type default))
  )
  (polyline (pts (xy 207.01 181.61) (xy 212.09 181.61))
    (stroke (width 0) (type default))
  )

  (wire (pts (xy 200.66 48.26) (xy 212.09 48.26))
    (stroke (width 0) (type default))
  )
  (wire (pts (xy 336.55 69.85) (xy 336.55 74.93))
    (stroke (width 0) (type default))
  )
  (polyline (pts (xy 205.74 247.65) (xy 205.74 255.27))
    (stroke (width 0) (type dash))
  )

  (wire (pts (xy 177.8 190.5) (xy 190.5 190.5))
    (stroke (width 0) (type default))
  )
  (polyline (pts (xy 199.39 181.61) (xy 204.47 181.61))
    (stroke (width 0) (type default))
  )

  (wire (pts (xy 203.2 55.88) (xy 203.2 53.34))
    (stroke (width 0) (type default))
  )
  (wire (pts (xy 31.75 48.26) (xy 34.29 48.26))
    (stroke (width 0) (type default))
  )
  (wire (pts (xy 252.73 57.15) (xy 252.73 54.61))
    (stroke (width 0) (type default))
  )
  (wire (pts (xy 36.83 201.93) (xy 36.83 199.39))
    (stroke (width 0) (type default))
  )
  (wire (pts (xy 53.34 181.61) (xy 53.34 182.88))
    (stroke (width 0) (type default))
  )
  (wire (pts (xy 153.67 50.8) (xy 153.67 53.34))
    (stroke (width 0) (type default))
  )
  (wire (pts (xy 83.82 50.8) (xy 80.01 50.8))
    (stroke (width 0) (type default))
  )
  (wire (pts (xy 144.78 36.83) (xy 153.67 36.83))
    (stroke (width 0) (type default))
  )
  (wire (pts (xy 252.73 52.07) (xy 252.73 54.61))
    (stroke (width 0) (type default))
  )
  (wire (pts (xy 194.31 36.83) (xy 203.2 36.83))
    (stroke (width 0) (type default))
  )
  (wire (pts (xy 328.93 55.88) (xy 328.93 64.77))
    (stroke (width 0) (type default))
  )
  (wire (pts (xy 134.62 91.44) (xy 134.62 93.98))
    (stroke (width 0) (type default))
  )
  (wire (pts (xy 29.21 173.99) (xy 29.21 176.53))
    (stroke (width 0) (type default))
  )
  (wire (pts (xy 284.48 34.29) (xy 284.48 36.83))
    (stroke (width 0) (type default))
  )
  (wire (pts (xy 304.8 64.77) (xy 312.42 64.77))
    (stroke (width 0) (type default))
  )
  (wire (pts (xy 287.02 59.69) (xy 271.78 59.69))
    (stroke (width 0) (type default))
  )
  (polyline (pts (xy 199.39 255.27) (xy 205.74 255.27))
    (stroke (width 0) (type dash))
  )

  (wire (pts (xy 29.21 181.61) (xy 29.21 186.69))
    (stroke (width 0) (type default))
  )
  (polyline (pts (xy 199.39 190.5) (xy 205.74 190.5))
    (stroke (width 0) (type dash))
  )
  (polyline (pts (xy 16.51 133.35) (xy 403.86 133.35))
    (stroke (width 0) (type dash))
  )
  (polyline (pts (xy 207.01 158.75) (xy 212.09 158.75))
    (stroke (width 0) (type default))
  )

  (wire (pts (xy 29.21 201.93) (xy 29.21 199.39))
    (stroke (width 0) (type default))
  )
  (wire (pts (xy 74.93 194.31) (xy 72.39 194.31))
    (stroke (width 0) (type default))
  )
  (polyline (pts (xy 199.39 233.68) (xy 205.74 233.68))
    (stroke (width 0) (type dash))
  )

  (wire (pts (xy 130.81 36.83) (xy 130.81 48.26))
    (stroke (width 0) (type default))
  )
  (wire (pts (xy 81.28 36.83) (xy 81.28 48.26))
    (stroke (width 0) (type default))
  )
  (wire (pts (xy 312.42 64.77) (xy 318.77 64.77))
    (stroke (width 0) (type default))
  )
  (wire (pts (xy 200.66 50.8) (xy 203.2 50.8))
    (stroke (width 0) (type default))
  )
  (wire (pts (xy 31.75 36.83) (xy 40.64 36.83))
    (stroke (width 0) (type default))
  )
  (wire (pts (xy 151.13 48.26) (xy 162.56 48.26))
    (stroke (width 0) (type default))
  )
  (wire (pts (xy 92.71 184.15) (xy 99.06 184.15))
    (stroke (width 0) (type default))
  )
  (wire (pts (xy 280.67 34.29) (xy 284.48 34.29))
    (stroke (width 0) (type default))
  )
  (wire (pts (xy 229.87 38.1) (xy 238.76 38.1))
    (stroke (width 0) (type default))
  )
  (wire (pts (xy 276.86 39.37) (xy 276.86 36.83))
    (stroke (width 0) (type default))
  )
  (wire (pts (xy 54.61 53.34) (xy 52.07 53.34))
    (stroke (width 0) (type default))
  )
  (wire (pts (xy 308.61 52.07) (xy 304.8 52.07))
    (stroke (width 0) (type default))
  )
  (wire (pts (xy 54.61 50.8) (xy 54.61 53.34))
    (stroke (width 0) (type default))
  )
  (wire (pts (xy 187.96 228.6) (xy 190.5 228.6))
    (stroke (width 0) (type default))
  )
  (wire (pts (xy 36.83 173.99) (xy 44.45 173.99))
    (stroke (width 0) (type default))
  )
  (wire (pts (xy 134.62 104.14) (xy 142.24 104.14))
    (stroke (width 0) (type default))
  )
  (wire (pts (xy 133.35 50.8) (xy 129.54 50.8))
    (stroke (width 0) (type default))
  )
  (wire (pts (xy 250.19 52.07) (xy 252.73 52.07))
    (stroke (width 0) (type default))
  )
  (wire (pts (xy 36.83 189.23) (xy 74.93 189.23))
    (stroke (width 0) (type default))
  )
  (wire (pts (xy 130.81 48.26) (xy 133.35 48.26))
    (stroke (width 0) (type default))
  )
  (polyline (pts (xy 207.01 160.02) (xy 204.47 158.75))
    (stroke (width 0) (type default))
  )
  (polyline (pts (xy 207.01 246.38) (xy 212.09 246.38))
    (stroke (width 0) (type default))
  )

  (wire (pts (xy 187.96 181.61) (xy 190.5 181.61))
    (stroke (width 0) (type default))
  )
  (wire (pts (xy 101.6 50.8) (xy 104.14 50.8))
    (stroke (width 0) (type default))
  )
  (wire (pts (xy 203.2 50.8) (xy 203.2 53.34))
    (stroke (width 0) (type default))
  )
  (wire (pts (xy 312.42 64.77) (xy 312.42 66.04))
    (stroke (width 0) (type default))
  )
  (wire (pts (xy 177.8 233.68) (xy 190.5 233.68))
    (stroke (width 0) (type default))
  )
  (polyline (pts (xy 207.01 226.06) (xy 204.47 224.79))
    (stroke (width 0) (type default))
  )

  (wire (pts (xy 177.8 167.64) (xy 190.5 167.64))
    (stroke (width 0) (type default))
  )
  (wire (pts (xy 92.71 173.99) (xy 99.06 173.99))
    (stroke (width 0) (type default))
  )
  (wire (pts (xy 36.83 181.61) (xy 36.83 189.23))
    (stroke (width 0) (type default))
  )
  (wire (pts (xy 284.48 52.07) (xy 287.02 52.07))
    (stroke (width 0) (type default))
  )
  (polyline (pts (xy 199.39 158.75) (xy 204.47 158.75))
    (stroke (width 0) (type default))
  )
  (polyline (pts (xy 199.39 167.64) (xy 205.74 167.64))
    (stroke (width 0) (type dash))
  )

  (wire (pts (xy 345.44 55.88) (xy 345.44 64.77))
    (stroke (width 0) (type default))
  )
  (wire (pts (xy 336.55 74.93) (xy 336.55 77.47))
    (stroke (width 0) (type default))
  )
  (wire (pts (xy 219.71 158.75) (xy 222.25 158.75))
    (stroke (width 0) (type default))
  )
  (wire (pts (xy 72.39 160.02) (xy 72.39 173.99))
    (stroke (width 0) (type default))
  )
  (wire (pts (xy 252.73 54.61) (xy 250.19 54.61))
    (stroke (width 0) (type default))
  )
  (wire (pts (xy 182.88 53.34) (xy 179.07 53.34))
    (stroke (width 0) (type default))
  )
  (wire (pts (xy 153.67 55.88) (xy 153.67 53.34))
    (stroke (width 0) (type default))
  )
  (wire (pts (xy 271.78 67.31) (xy 287.02 67.31))
    (stroke (width 0) (type default))
  )
  (wire (pts (xy 132.08 91.44) (xy 134.62 91.44))
    (stroke (width 0) (type default))
  )
  (wire (pts (xy 345.44 69.85) (xy 345.44 72.39))
    (stroke (width 0) (type default))
  )
  (wire (pts (xy 374.65 59.69) (xy 360.68 59.69))
    (stroke (width 0) (type default))
  )
  (wire (pts (xy 72.39 160.02) (xy 81.28 160.02))
    (stroke (width 0) (type default))
  )
  (wire (pts (xy 130.81 34.29) (xy 130.81 36.83))
    (stroke (width 0) (type default))
  )
  (polyline (pts (xy 199.39 212.09) (xy 205.74 212.09))
    (stroke (width 0) (type dash))
  )

  (wire (pts (xy 219.71 224.79) (xy 222.25 224.79))
    (stroke (width 0) (type default))
  )
  (wire (pts (xy 123.19 195.58) (xy 138.43 195.58))
    (stroke (width 0) (type default))
  )
  (wire (pts (xy 72.39 173.99) (xy 74.93 173.99))
    (stroke (width 0) (type default))
  )
  (wire (pts (xy 360.68 67.31) (xy 374.65 67.31))
    (stroke (width 0) (type default))
  )
  (wire (pts (xy 138.43 200.66) (xy 123.19 200.66))
    (stroke (width 0) (type default))
  )
  (wire (pts (xy 134.62 99.06) (xy 134.62 104.14))
    (stroke (width 0) (type default))
  )
  (polyline (pts (xy 207.01 182.88) (xy 204.47 181.61))
    (stroke (width 0) (type default))
  )

  (wire (pts (xy 29.21 173.99) (xy 36.83 173.99))
    (stroke (width 0) (type default))
  )
  (wire (pts (xy 203.2 36.83) (xy 203.2 50.8))
    (stroke (width 0) (type default))
  )
  (wire (pts (xy 187.96 203.2) (xy 190.5 203.2))
    (stroke (width 0) (type default))
  )
  (wire (pts (xy 44.45 173.99) (xy 44.45 176.53))
    (stroke (width 0) (type default))
  )
  (wire (pts (xy 44.45 191.77) (xy 44.45 194.31))
    (stroke (width 0) (type default))
  )
  (wire (pts (xy 271.78 64.77) (xy 287.02 64.77))
    (stroke (width 0) (type default))
  )
  (polyline (pts (xy 205.74 182.88) (xy 205.74 190.5))
    (stroke (width 0) (type dash))
  )

  (wire (pts (xy 360.68 62.23) (xy 374.65 62.23))
    (stroke (width 0) (type default))
  )
  (wire (pts (xy 304.8 80.01) (xy 307.34 80.01))
    (stroke (width 0) (type default))
  )
  (polyline (pts (xy 207.01 247.65) (xy 204.47 246.38))
    (stroke (width 0) (type default))
  )

  (wire (pts (xy 86.36 160.02) (xy 93.98 160.02))
    (stroke (width 0) (type default))
  )
  (wire (pts (xy 308.61 54.61) (xy 304.8 54.61))
    (stroke (width 0) (type default))
  )
  (wire (pts (xy 219.71 203.2) (xy 222.25 203.2))
    (stroke (width 0) (type default))
  )
  (wire (pts (xy 180.34 34.29) (xy 180.34 36.83))
    (stroke (width 0) (type default))
  )
  (wire (pts (xy 34.29 50.8) (xy 30.48 50.8))
    (stroke (width 0) (type default))
  )
  (wire (pts (xy 180.34 36.83) (xy 189.23 36.83))
    (stroke (width 0) (type default))
  )
  (wire (pts (xy 323.85 64.77) (xy 328.93 64.77))
    (stroke (width 0) (type default))
  )
  (wire (pts (xy 123.19 193.04) (xy 138.43 193.04))
    (stroke (width 0) (type default))
  )
  (wire (pts (xy 276.86 44.45) (xy 276.86 46.99))
    (stroke (width 0) (type default))
  )
  (wire (pts (xy 304.8 72.39) (xy 345.44 72.39))
    (stroke (width 0) (type default))
  )
  (wire (pts (xy 52.07 48.26) (xy 63.5 48.26))
    (stroke (width 0) (type default))
  )
  (wire (pts (xy 44.45 201.93) (xy 44.45 199.39))
    (stroke (width 0) (type default))
  )
  (wire (pts (xy 31.75 34.29) (xy 31.75 36.83))
    (stroke (width 0) (type default))
  )
  (wire (pts (xy 53.34 173.99) (xy 53.34 176.53))
    (stroke (width 0) (type default))
  )
  (wire (pts (xy 284.48 80.01) (xy 287.02 80.01))
    (stroke (width 0) (type default))
  )
  (wire (pts (xy 187.96 250.19) (xy 190.5 250.19))
    (stroke (width 0) (type default))
  )
  (wire (pts (xy 104.14 50.8) (xy 104.14 53.34))
    (stroke (width 0) (type default))
  )
  (wire (pts (xy 147.32 104.14) (xy 152.4 104.14))
    (stroke (width 0) (type default))
  )
  (wire (pts (xy 152.4 114.3) (xy 154.94 114.3))
    (stroke (width 0) (type default))
  )
  (wire (pts (xy 287.02 57.15) (xy 271.78 57.15))
    (stroke (width 0) (type default))
  )
  (wire (pts (xy 95.25 36.83) (xy 104.14 36.83))
    (stroke (width 0) (type default))
  )
  (wire (pts (xy 307.34 80.01) (xy 307.34 85.09))
    (stroke (width 0) (type default))
  )
  (wire (pts (xy 69.85 177.8) (xy 74.93 177.8))
    (stroke (width 0) (type default))
  )
  (wire (pts (xy 72.39 156.21) (xy 72.39 160.02))
    (stroke (width 0) (type default))
  )
  (polyline (pts (xy 207.01 224.79) (xy 212.09 224.79))
    (stroke (width 0) (type default))
  )

  (wire (pts (xy 284.48 85.09) (xy 284.48 80.01))
    (stroke (width 0) (type default))
  )
  (wire (pts (xy 81.28 36.83) (xy 90.17 36.83))
    (stroke (width 0) (type default))
  )
  (wire (pts (xy 152.4 116.84) (xy 152.4 114.3))
    (stroke (width 0) (type default))
  )
  (wire (pts (xy 177.8 212.09) (xy 190.5 212.09))
    (stroke (width 0) (type default))
  )
  (polyline (pts (xy 205.74 204.47) (xy 205.74 212.09))
    (stroke (width 0) (type dash))
  )

  (wire (pts (xy 229.87 38.1) (xy 229.87 49.53))
    (stroke (width 0) (type default))
  )
  (wire (pts (xy 180.34 36.83) (xy 180.34 48.26))
    (stroke (width 0) (type default))
  )
  (polyline (pts (xy 199.39 246.38) (xy 204.47 246.38))
    (stroke (width 0) (type default))
  )
  (polyline (pts (xy 207.01 204.47) (xy 204.47 203.2))
    (stroke (width 0) (type default))
  )

  (wire (pts (xy 153.67 53.34) (xy 151.13 53.34))
    (stroke (width 0) (type default))
  )
  (wire (pts (xy 104.14 55.88) (xy 104.14 53.34))
    (stroke (width 0) (type default))
  )
  (wire (pts (xy 276.86 36.83) (xy 284.48 36.83))
    (stroke (width 0) (type default))
  )

  (rectangle (start 153.67 87.63) (end 194.31 97.79)
    (stroke (width 0) (type dash))
    (fill (type none))
  )
  (rectangle (start 16.51 66.04) (end 99.06 76.2)
    (stroke (width 0) (type dash))
    (fill (type none))
  )
  (rectangle (start 16.51 30.48) (end 264.16 64.77)
    (stroke (width 0) (type default))
    (fill (type none))
  )
  (rectangle (start 359.41 55.88) (end 391.16 72.39)
    (stroke (width 0) (type dash))
    (fill (type none))
  )
  (rectangle (start 120.65 189.23) (end 152.4 205.74)
    (stroke (width 0) (type dash))
    (fill (type none))
  )
  (rectangle (start 267.97 30.48) (end 400.05 92.71)
    (stroke (width 0) (type default))
    (fill (type none))
  )

  (text "Not used pins PX MUST be configured as outputs!\n" (at 29.21 222.25 0)
    (effects (font (size 2.0066 2.0066)) (justify left bottom))
  )
  (text "Current Measurement" (at 15.24 21.59 0)
    (effects (font (size 2.9972 2.9972) (thickness 0.5994) bold) (justify left bottom))
  )
  (text "ADC inputs TPs" (at 359.41 54.61 0)
    (effects (font (size 2.0066 2.0066)) (justify left bottom))
  )
  (text "SWITCHING BLOCKS" (at 182.245 145.415 0)
    (effects (font (size 2.9972 2.9972)) (justify left bottom))
  )
  (text "Key transistors' polarization TPs" (at 113.03 187.96 0)
    (effects (font (size 2.0066 2.0066)) (justify left bottom))
  )
  (text "ADC" (at 267.97 29.21 0)
    (effects (font (size 2.9972 2.9972)) (justify left bottom))
  )
  (text "GPIO EXPANDER" (at 44.45 151.13 0)
    (effects (font (size 2.9972 2.9972)) (justify left bottom))
  )
  (text "To perform more accurate measurement, the sensor can be replaced\nwith *A3 part (MPN: TMCS1100A3-Q1). Note that it will result in\n measured currents range reduction (to up to 15.5A unidirect.)."
    (at 17.78 74.93 0)
    (effects (font (size 1.4986 1.4986)) (justify left bottom))
  )
  (text "Hall-Effect current sensors" (at 16.51 29.21 0)
    (effects (font (size 2.9972 2.9972)) (justify left bottom))
  )
  (text "info:\nADC reference voltage: 2V5\nAssumed max input voltage: 18V\nVoltage divider max out value: 2.402V"
    (at 154.94 96.52 0)
    (effects (font (size 1.27 1.27)) (justify left bottom))
  )
  (text "Power Cycling" (at 16.51 139.7 0)
    (effects (font (size 2.9972 2.9972) (thickness 0.5994) bold) (justify left bottom))
  )

  (label "PC_5" (at 177.8 255.27 0) (fields_autoplaced)
    (effects (font (size 1.27 1.27)) (justify left bottom))
  )
  (label "C_ADC4" (at 271.78 59.69 0) (fields_autoplaced)
    (effects (font (size 1.27 1.27)) (justify left bottom))
  )
  (label "C_ADC3" (at 271.78 62.23 0) (fields_autoplaced)
    (effects (font (size 1.27 1.27)) (justify left bottom))
  )
  (label "PC_2" (at 177.8 190.5 0) (fields_autoplaced)
    (effects (font (size 1.27 1.27)) (justify left bottom))
  )
  (label "C_ADC3" (at 162.56 48.26 180) (fields_autoplaced)
    (effects (font (size 1.27 1.27)) (justify right bottom))
  )
  (label "PC_1" (at 177.8 167.64 0) (fields_autoplaced)
    (effects (font (size 1.27 1.27)) (justify left bottom))
  )
  (label "PC_1" (at 123.19 193.04 0) (fields_autoplaced)
    (effects (font (size 1.27 1.27)) (justify left bottom))
  )
  (label "V_ADC1" (at 271.78 74.93 0) (fields_autoplaced)
    (effects (font (size 1.27 1.27)) (justify left bottom))
  )
  (label "PC_3" (at 177.8 212.09 0) (fields_autoplaced)
    (effects (font (size 1.27 1.27)) (justify left bottom))
  )
  (label "C_ADC4" (at 212.09 48.26 180) (fields_autoplaced)
    (effects (font (size 1.27 1.27)) (justify right bottom))
  )
  (label "PC_2" (at 123.19 195.58 0) (fields_autoplaced)
    (effects (font (size 1.27 1.27)) (justify left bottom))
  )
  (label "C_ADC3" (at 360.68 64.77 0) (fields_autoplaced)
    (effects (font (size 1.27 1.27)) (justify left bottom))
  )
  (label "PC_2" (at 99.06 181.61 180) (fields_autoplaced)
    (effects (font (size 1.27 1.27)) (justify right bottom))
  )
  (label "C_ADC1" (at 271.78 67.31 0) (fields_autoplaced)
    (effects (font (size 1.27 1.27)) (justify left bottom))
  )
  (label "C_ADC5" (at 271.78 57.15 0) (fields_autoplaced)
    (effects (font (size 1.27 1.27)) (justify left bottom))
  )
  (label "V_ADC1" (at 166.37 104.14 180) (fields_autoplaced)
    (effects (font (size 1.27 1.27)) (justify right bottom))
  )
  (label "C_ADC5" (at 261.62 49.53 180) (fields_autoplaced)
    (effects (font (size 1.27 1.27)) (justify right bottom))
  )
  (label "PC_3" (at 123.19 198.12 0) (fields_autoplaced)
    (effects (font (size 1.27 1.27)) (justify left bottom))
  )
  (label "PC_3" (at 99.06 179.07 180) (fields_autoplaced)
    (effects (font (size 1.27 1.27)) (justify right bottom))
  )
  (label "PC_5" (at 123.19 203.2 0) (fields_autoplaced)
    (effects (font (size 1.27 1.27)) (justify left bottom))
  )
  (label "PC_1" (at 99.06 184.15 180) (fields_autoplaced)
    (effects (font (size 1.27 1.27)) (justify right bottom))
  )
  (label "C_ADC2" (at 360.68 62.23 0) (fields_autoplaced)
    (effects (font (size 1.27 1.27)) (justify left bottom))
  )
  (label "C_ADC2" (at 271.78 64.77 0) (fields_autoplaced)
    (effects (font (size 1.27 1.27)) (justify left bottom))
  )
  (label "PC_4" (at 99.06 176.53 180) (fields_autoplaced)
    (effects (font (size 1.27 1.27)) (justify right bottom))
  )
  (label "PC_4" (at 177.8 233.68 0) (fields_autoplaced)
    (effects (font (size 1.27 1.27)) (justify left bottom))
  )
  (label "C_ADC5" (at 360.68 69.85 0) (fields_autoplaced)
    (effects (font (size 1.27 1.27)) (justify left bottom))
  )
  (label "PC_5" (at 99.06 173.99 180) (fields_autoplaced)
    (effects (font (size 1.27 1.27)) (justify right bottom))
  )
  (label "PC_4" (at 123.19 200.66 0) (fields_autoplaced)
    (effects (font (size 1.27 1.27)) (justify left bottom))
  )
  (label "C_ADC2" (at 113.03 48.26 180) (fields_autoplaced)
    (effects (font (size 1.27 1.27)) (justify right bottom))
  )
  (label "C_ADC1" (at 360.68 59.69 0) (fields_autoplaced)
    (effects (font (size 1.27 1.27)) (justify left bottom))
  )
  (label "C_ADC1" (at 63.5 48.26 180) (fields_autoplaced)
    (effects (font (size 1.27 1.27)) (justify right bottom))
  )
  (label "C_ADC4" (at 360.68 67.31 0) (fields_autoplaced)
    (effects (font (size 1.27 1.27)) (justify left bottom))
  )

  (global_label "VCC12V0" (shape input) (at 132.08 91.44 180) (fields_autoplaced)
    (effects (font (size 1.27 1.27)) (justify right))
    (property "Intersheetrefs" "${INTERSHEET_REFS}" (at 121.4101 91.3606 0)
      (effects (font (size 1.27 1.27)) (justify right) hide)
    )
  )
  (global_label "VCC12V0" (shape input) (at 187.96 246.38 180) (fields_autoplaced)
    (effects (font (size 1.27 1.27)) (justify right))
    (property "Intersheetrefs" "${INTERSHEET_REFS}" (at -48.26 97.79 0)
      (effects (font (size 1.27 1.27)) hide)
    )
  )
  (global_label "C_MEAS_4" (shape input) (at 222.25 224.79 0) (fields_autoplaced)
    (effects (font (size 1.27 1.27)) (justify left))
    (property "Intersheetrefs" "${INTERSHEET_REFS}" (at 233.8942 224.79 0)
      (effects (font (size 1.27 1.27)) (justify left) hide)
    )
  )
  (global_label "C_MEAS_3" (shape input) (at 222.25 203.2 0) (fields_autoplaced)
    (effects (font (size 1.27 1.27)) (justify left))
    (property "Intersheetrefs" "${INTERSHEET_REFS}" (at 233.8942 203.2 0)
      (effects (font (size 1.27 1.27)) (justify left) hide)
    )
  )
  (global_label "C_MEAS_2" (shape input) (at 80.01 50.8 180) (fields_autoplaced)
    (effects (font (size 1.27 1.27)) (justify right))
    (property "Intersheetrefs" "${INTERSHEET_REFS}" (at 68.3658 50.8 0)
      (effects (font (size 1.27 1.27)) (justify right) hide)
    )
  )
  (global_label "VCC12V0" (shape input) (at 187.96 158.75 180) (fields_autoplaced)
    (effects (font (size 1.27 1.27)) (justify right))
    (property "Intersheetrefs" "${INTERSHEET_REFS}" (at -48.26 10.16 0)
      (effects (font (size 1.27 1.27)) hide)
    )
  )
  (global_label "LOAD_3" (shape input) (at 129.54 53.34 180) (fields_autoplaced)
    (effects (font (size 1.27 1.27)) (justify right))
    (property "Intersheetrefs" "${INTERSHEET_REFS}" (at 120.3147 53.34 0)
      (effects (font (size 1.27 1.27)) (justify right) hide)
    )
  )
  (global_label "LOAD_5" (shape input) (at 228.6 54.61 180) (fields_autoplaced)
    (effects (font (size 1.27 1.27)) (justify right))
    (property "Intersheetrefs" "${INTERSHEET_REFS}" (at 219.3747 54.61 0)
      (effects (font (size 1.27 1.27)) (justify right) hide)
    )
  )
  (global_label "VCC3V3" (shape input) (at 72.39 156.21 180) (fields_autoplaced)
    (effects (font (size 1.27 1.27)) (justify right))
    (property "Intersheetrefs" "${INTERSHEET_REFS}" (at 62.9228 156.21 0)
      (effects (font (size 1.27 1.27)) (justify right) hide)
    )
  )
  (global_label "C_MEAS_4" (shape input) (at 179.07 50.8 180) (fields_autoplaced)
    (effects (font (size 1.27 1.27)) (justify right))
    (property "Intersheetrefs" "${INTERSHEET_REFS}" (at 167.4258 50.8 0)
      (effects (font (size 1.27 1.27)) (justify right) hide)
    )
  )
  (global_label "VCC3V3" (shape input) (at 187.96 250.19 180) (fields_autoplaced)
    (effects (font (size 1.27 1.27)) (justify right))
    (property "Intersheetrefs" "${INTERSHEET_REFS}" (at -33.02 97.79 0)
      (effects (font (size 1.27 1.27)) hide)
    )
  )
  (global_label "VCC3V3" (shape input) (at 187.96 228.6 180) (fields_autoplaced)
    (effects (font (size 1.27 1.27)) (justify right))
    (property "Intersheetrefs" "${INTERSHEET_REFS}" (at -33.02 76.2 0)
      (effects (font (size 1.27 1.27)) hide)
    )
  )
  (global_label "SDA" (shape input) (at 308.61 52.07 0) (fields_autoplaced)
    (effects (font (size 1.27 1.27)) (justify left))
    (property "Intersheetrefs" "${INTERSHEET_REFS}" (at 30.48 -3.81 0)
      (effects (font (size 1.27 1.27)) hide)
    )
  )
  (global_label "VCC3V3" (shape input) (at 187.96 207.01 180) (fields_autoplaced)
    (effects (font (size 1.27 1.27)) (justify right))
    (property "Intersheetrefs" "${INTERSHEET_REFS}" (at -33.02 54.61 0)
      (effects (font (size 1.27 1.27)) hide)
    )
  )
  (global_label "C_MEAS_1" (shape input) (at 30.48 50.8 180) (fields_autoplaced)
    (effects (font (size 1.27 1.27)) (justify right))
    (property "Intersheetrefs" "${INTERSHEET_REFS}" (at -11.43 -1.27 0)
      (effects (font (size 1.27 1.27)) hide)
    )
  )
  (global_label "C_MEAS_5" (shape input) (at 228.6 52.07 180) (fields_autoplaced)
    (effects (font (size 1.27 1.27)) (justify right))
    (property "Intersheetrefs" "${INTERSHEET_REFS}" (at 216.9558 52.07 0)
      (effects (font (size 1.27 1.27)) (justify right) hide)
    )
  )
  (global_label "VCC12V0" (shape input) (at 187.96 224.79 180) (fields_autoplaced)
    (effects (font (size 1.27 1.27)) (justify right))
    (property "Intersheetrefs" "${INTERSHEET_REFS}" (at -48.26 76.2 0)
      (effects (font (size 1.27 1.27)) hide)
    )
  )
  (global_label "LOAD_1" (shape input) (at 30.48 53.34 180) (fields_autoplaced)
    (effects (font (size 1.27 1.27)) (justify right))
    (property "Intersheetrefs" "${INTERSHEET_REFS}" (at -11.43 -3.81 0)
      (effects (font (size 1.27 1.27)) hide)
    )
  )
  (global_label "C_MEAS_5" (shape input) (at 222.25 246.38 0) (fields_autoplaced)
    (effects (font (size 1.27 1.27)) (justify left))
    (property "Intersheetrefs" "${INTERSHEET_REFS}" (at 233.8942 246.38 0)
      (effects (font (size 1.27 1.27)) (justify left) hide)
    )
  )
  (global_label "VCC12V0" (shape input) (at 187.96 203.2 180) (fields_autoplaced)
    (effects (font (size 1.27 1.27)) (justify right))
    (property "Intersheetrefs" "${INTERSHEET_REFS}" (at -48.26 54.61 0)
      (effects (font (size 1.27 1.27)) hide)
    )
  )
  (global_label "VCC3V3" (shape input) (at 328.93 55.88 90) (fields_autoplaced)
    (effects (font (size 1.27 1.27)) (justify left))
    (property "Intersheetrefs" "${INTERSHEET_REFS}" (at 43.18 11.43 0)
      (effects (font (size 1.27 1.27)) hide)
    )
  )
  (global_label "VCC3V3" (shape input) (at 180.34 34.29 180) (fields_autoplaced)
    (effects (font (size 1.27 1.27)) (justify right))
    (property "Intersheetrefs" "${INTERSHEET_REFS}" (at 170.8728 34.29 0)
      (effects (font (size 1.27 1.27)) (justify right) hide)
    )
  )
  (global_label "SCL" (shape input) (at 308.61 54.61 0) (fields_autoplaced)
    (effects (font (size 1.27 1.27)) (justify left))
    (property "Intersheetrefs" "${INTERSHEET_REFS}" (at 30.48 -3.81 0)
      (effects (font (size 1.27 1.27)) hide)
    )
  )
  (global_label "SDA" (shape input) (at 69.85 177.8 180) (fields_autoplaced)
    (effects (font (size 1.27 1.27)) (justify right))
    (property "Intersheetrefs" "${INTERSHEET_REFS}" (at 2.54 -2.54 0)
      (effects (font (size 1.27 1.27)) hide)
    )
  )
  (global_label "VCC3V3" (shape input) (at 336.55 55.88 90) (fields_autoplaced)
    (effects (font (size 1.27 1.27)) (justify left))
    (property "Intersheetrefs" "${INTERSHEET_REFS}" (at 46.99 11.43 0)
      (effects (font (size 1.27 1.27)) hide)
    )
  )
  (global_label "VCC3V3" (shape input) (at 187.96 185.42 180) (fields_autoplaced)
    (effects (font (size 1.27 1.27)) (justify right))
    (property "Intersheetrefs" "${INTERSHEET_REFS}" (at -33.02 33.02 0)
      (effects (font (size 1.27 1.27)) hide)
    )
  )
  (global_label "VCC3V3" (shape input) (at 229.87 35.56 180) (fields_autoplaced)
    (effects (font (size 1.27 1.27)) (justify right))
    (property "Intersheetrefs" "${INTERSHEET_REFS}" (at 220.4028 35.56 0)
      (effects (font (size 1.27 1.27)) (justify right) hide)
    )
  )
  (global_label "C_MEAS_1" (shape input) (at 222.25 158.75 0) (fields_autoplaced)
    (effects (font (size 1.27 1.27)) (justify left))
    (property "Intersheetrefs" "${INTERSHEET_REFS}" (at 233.8942 158.75 0)
      (effects (font (size 1.27 1.27)) (justify left) hide)
    )
  )
  (global_label "VCC3V3" (shape input) (at 130.81 34.29 180) (fields_autoplaced)
    (effects (font (size 1.27 1.27)) (justify right))
    (property "Intersheetrefs" "${INTERSHEET_REFS}" (at 121.3428 34.29 0)
      (effects (font (size 1.27 1.27)) (justify right) hide)
    )
  )
  (global_label "VCC3V3" (shape input) (at 81.28 34.29 180) (fields_autoplaced)
    (effects (font (size 1.27 1.27)) (justify right))
    (property "Intersheetrefs" "${INTERSHEET_REFS}" (at 71.8128 34.29 0)
      (effects (font (size 1.27 1.27)) (justify right) hide)
    )
  )
  (global_label "C_MEAS_2" (shape input) (at 222.25 181.61 0) (fields_autoplaced)
    (effects (font (size 1.27 1.27)) (justify left))
    (property "Intersheetrefs" "${INTERSHEET_REFS}" (at 233.8942 181.61 0)
      (effects (font (size 1.27 1.27)) (justify left) hide)
    )
  )
  (global_label "VCC3V3" (shape input) (at 31.75 34.29 180) (fields_autoplaced)
    (effects (font (size 1.27 1.27)) (justify right))
    (property "Intersheetrefs" "${INTERSHEET_REFS}" (at 22.2828 34.29 0)
      (effects (font (size 1.27 1.27)) (justify right) hide)
    )
  )
  (global_label "VCC3V3" (shape input) (at 280.67 34.29 180) (fields_autoplaced)
    (effects (font (size 1.27 1.27)) (justify right))
    (property "Intersheetrefs" "${INTERSHEET_REFS}" (at 271.2028 34.29 0)
      (effects (font (size 1.27 1.27)) (justify right) hide)
    )
  )
  (global_label "VCC3V3" (shape input) (at 187.96 162.56 180) (fields_autoplaced)
    (effects (font (size 1.27 1.27)) (justify right))
    (property "Intersheetrefs" "${INTERSHEET_REFS}" (at -33.02 10.16 0)
      (effects (font (size 1.27 1.27)) hide)
    )
  )
  (global_label "C_MEAS_3" (shape input) (at 129.54 50.8 180) (fields_autoplaced)
    (effects (font (size 1.27 1.27)) (justify right))
    (property "Intersheetrefs" "${INTERSHEET_REFS}" (at 117.8958 50.8 0)
      (effects (font (size 1.27 1.27)) (justify right) hide)
    )
  )
  (global_label "LOAD_2" (shape input) (at 80.01 53.34 180) (fields_autoplaced)
    (effects (font (size 1.27 1.27)) (justify right))
    (property "Intersheetrefs" "${INTERSHEET_REFS}" (at 70.7847 53.34 0)
      (effects (font (size 1.27 1.27)) (justify right) hide)
    )
  )
  (global_label "SCL" (shape input) (at 69.85 180.34 180) (fields_autoplaced)
    (effects (font (size 1.27 1.27)) (justify right))
    (property "Intersheetrefs" "${INTERSHEET_REFS}" (at 2.54 2.54 0)
      (effects (font (size 1.27 1.27)) hide)
    )
  )
  (global_label "LOAD_4" (shape input) (at 179.07 53.34 180) (fields_autoplaced)
    (effects (font (size 1.27 1.27)) (justify right))
    (property "Intersheetrefs" "${INTERSHEET_REFS}" (at 169.8447 53.34 0)
      (effects (font (size 1.27 1.27)) (justify right) hide)
    )
  )
  (global_label "VCC3V3" (shape input) (at 345.44 55.88 90) (fields_autoplaced)
    (effects (font (size 1.27 1.27)) (justify left))
    (property "Intersheetrefs" "${INTERSHEET_REFS}" (at 52.07 11.43 0)
      (effects (font (size 1.27 1.27)) hide)
    )
  )
  (global_label "VCC12V0" (shape input) (at 187.96 181.61 180) (fields_autoplaced)
    (effects (font (size 1.27 1.27)) (justify right))
    (property "Intersheetrefs" "${INTERSHEET_REFS}" (at -48.26 33.02 0)
      (effects (font (size 1.27 1.27)) hide)
    )
  )

  (symbol (lib_id "antmicroInterfaceIOExpanders:TCA9534PWR_TSSOP") (at 74.93 173.99 0) (unit 1)
    (in_bom yes) (on_board yes) (dnp no)
    (property "Reference" "U10" (at 83.82 167.64 0)
      (effects (font (size 1.27 1.27)))
    )
    (property "Value" "TCA9534PWR_TSSOP" (at 107.95 181.61 0)
      (effects (font (size 1.27 1.27) (thickness 0.15)) (justify left bottom) hide)
    )
    (property "Footprint" "antmicro-footprints:TSSOP-16_4.4x5mm_P0.65mm" (at 107.95 184.15 0)
      (effects (font (size 1.27 1.27) (thickness 0.15)) (justify left bottom) hide)
    )
    (property "Datasheet" "http://www.ti.com/lit/ds/symlink/tca9534.pdf" (at 107.95 186.69 0)
      (effects (font (size 1.27 1.27) (thickness 0.15)) (justify left bottom) hide)
    )
    (property "MPN" "TCA9534PWR" (at 83.82 170.18 0)
      (effects (font (size 1.27 1.27) (thickness 0.15)))
    )
    (property "Manufacturer" "Texas Instruments" (at 107.95 189.23 0)
      (effects (font (size 1.27 1.27) (thickness 0.15)) (justify left bottom) hide)
    )
    (property "Author" "Antmicro" (at 107.95 191.77 0)
      (effects (font (size 1.27 1.27) (thickness 0.15)) (justify left bottom) hide)
    )
    (property "License" "Apache-2.0" (at 107.95 194.31 0)
      (effects (font (size 1.27 1.27) (thickness 0.15)) (justify left bottom) hide)
    )
    (pin "1")
    (pin "10")
    (pin "11")
    (pin "12")
    (pin "13")
    (pin "14")
    (pin "15")
    (pin "16")
    (pin "2")
    (pin "3")
    (pin "4")
    (pin "5")
    (pin "6")
    (pin "7")
    (pin "8")
    (pin "9")
    (instances
      (project "d1600e-psu-breakout-board"
        (path ""
          (reference "U10") (unit 1)
        )
      )
    )
  )

  (symbol (lib_name "R_0R_0402_6") (lib_id "antmicroResistors0402:R_0R_0402") (at 29.21 176.53 270) (unit 1)
    (in_bom no) (on_board yes) (dnp yes)
    (property "Reference" "R13" (at 30.48 176.53 90)
      (effects (font (size 1.27 1.27)) (justify left))
    )
    (property "Value" "R_0R_0402" (at 16.51 196.85 0)
      (effects (font (size 1.27 1.27) (thickness 0.15)) (justify left bottom) hide)
    )
    (property "Footprint" "antmicro-footprints:R_0402_1005Metric" (at 13.97 196.85 0)
      (effects (font (size 1.27 1.27) (thickness 0.15)) (justify left bottom) hide)
    )
    (property "Datasheet" "https://industrial.panasonic.com/cdbs/www-data/pdf/RDA0000/AOA0000C301.pdf" (at 11.43 196.85 0)
      (effects (font (size 1.27 1.27) (thickness 0.15)) (justify left bottom) hide)
    )
    (property "Manufacturer" "Panasonic" (at 6.35 196.85 0)
      (effects (font (size 1.27 1.27) (thickness 0.15)) (justify left bottom) hide)
    )
    (property "MPN" "ERJ2GE0R00X" (at 8.89 196.85 0)
      (effects (font (size 1.27 1.27) (thickness 0.15)) (justify left bottom) hide)
    )
    (property "Val" "0R" (at 30.48 179.07 90)
      (effects (font (size 1.27 1.27) (thickness 0.15)) (justify left))
    )
    (property "DNP" "DNP" (at 30.48 181.61 90)
      (effects (font (size 1.27 1.27)) (justify left))
    )
    (property "License" "Apache-2.0" (at 3.81 196.85 0)
      (effects (font (size 1.27 1.27) (thickness 0.15)) (justify left bottom) hide)
    )
    (property "Author" "Antmicro" (at 1.27 196.85 0)
      (effects (font (size 1.27 1.27) (thickness 0.15)) (justify left bottom) hide)
    )
    (property "Tolerance" "~" (at 19.05 196.85 0)
      (effects (font (size 1.27 1.27)) (justify left bottom) hide)
    )
    (property "Current" "1A" (at -1.27 196.85 0)
      (effects (font (size 1.27 1.27) (thickness 0.15)) (justify left bottom) hide)
    )
    (pin "1")
    (pin "2")
    (instances
      (project "d1600e-psu-breakout-board"
        (path ""
          (reference "R13") (unit 1)
        )
      )
    )
  )

  (symbol (lib_name "R_0R_0402_7") (lib_id "antmicroResistors0402:R_0R_0402") (at 36.83 176.53 270) (unit 1)
    (in_bom no) (on_board yes) (dnp yes)
    (property "Reference" "R15" (at 38.1 176.53 90)
      (effects (font (size 1.27 1.27)) (justify left))
    )
    (property "Value" "R_0R_0402" (at 24.13 196.85 0)
      (effects (font (size 1.27 1.27) (thickness 0.15)) (justify left bottom) hide)
    )
    (property "Footprint" "antmicro-footprints:R_0402_1005Metric" (at 21.59 196.85 0)
      (effects (font (size 1.27 1.27) (thickness 0.15)) (justify left bottom) hide)
    )
    (property "Datasheet" "https://industrial.panasonic.com/cdbs/www-data/pdf/RDA0000/AOA0000C301.pdf" (at 19.05 196.85 0)
      (effects (font (size 1.27 1.27) (thickness 0.15)) (justify left bottom) hide)
    )
    (property "Manufacturer" "Panasonic" (at 13.97 196.85 0)
      (effects (font (size 1.27 1.27) (thickness 0.15)) (justify left bottom) hide)
    )
    (property "MPN" "ERJ2GE0R00X" (at 16.51 196.85 0)
      (effects (font (size 1.27 1.27) (thickness 0.15)) (justify left bottom) hide)
    )
    (property "Val" "0R" (at 38.1 179.07 90)
      (effects (font (size 1.27 1.27) (thickness 0.15)) (justify left))
    )
    (property "DNP" "DNP" (at 38.1 181.61 90)
      (effects (font (size 1.27 1.27)) (justify left))
    )
    (property "License" "Apache-2.0" (at 11.43 196.85 0)
      (effects (font (size 1.27 1.27) (thickness 0.15)) (justify left bottom) hide)
    )
    (property "Author" "Antmicro" (at 8.89 196.85 0)
      (effects (font (size 1.27 1.27) (thickness 0.15)) (justify left bottom) hide)
    )
    (property "Tolerance" "~" (at 26.67 196.85 0)
      (effects (font (size 1.27 1.27)) (justify left bottom) hide)
    )
    (property "Current" "1A" (at 6.35 196.85 0)
      (effects (font (size 1.27 1.27) (thickness 0.15)) (justify left bottom) hide)
    )
    (pin "1")
    (pin "2")
    (instances
      (project "d1600e-psu-breakout-board"
        (path ""
          (reference "R15") (unit 1)
        )
      )
    )
  )

  (symbol (lib_name "R_0R_0402_8") (lib_id "antmicroResistors0402:R_0R_0402") (at 44.45 176.53 270) (unit 1)
    (in_bom no) (on_board yes) (dnp yes)
    (property "Reference" "R17" (at 45.72 176.53 90)
      (effects (font (size 1.27 1.27)) (justify left))
    )
    (property "Value" "R_0R_0402" (at 31.75 196.85 0)
      (effects (font (size 1.27 1.27) (thickness 0.15)) (justify left bottom) hide)
    )
    (property "Footprint" "antmicro-footprints:R_0402_1005Metric" (at 29.21 196.85 0)
      (effects (font (size 1.27 1.27) (thickness 0.15)) (justify left bottom) hide)
    )
    (property "Datasheet" "https://industrial.panasonic.com/cdbs/www-data/pdf/RDA0000/AOA0000C301.pdf" (at 26.67 196.85 0)
      (effects (font (size 1.27 1.27) (thickness 0.15)) (justify left bottom) hide)
    )
    (property "Manufacturer" "Panasonic" (at 21.59 196.85 0)
      (effects (font (size 1.27 1.27) (thickness 0.15)) (justify left bottom) hide)
    )
    (property "MPN" "ERJ2GE0R00X" (at 24.13 196.85 0)
      (effects (font (size 1.27 1.27) (thickness 0.15)) (justify left bottom) hide)
    )
    (property "Val" "0R" (at 45.72 179.07 90)
      (effects (font (size 1.27 1.27) (thickness 0.15)) (justify left))
    )
    (property "DNP" "DNP" (at 45.72 181.61 90)
      (effects (font (size 1.27 1.27)) (justify left))
    )
    (property "License" "Apache-2.0" (at 19.05 196.85 0)
      (effects (font (size 1.27 1.27) (thickness 0.15)) (justify left bottom) hide)
    )
    (property "Author" "Antmicro" (at 16.51 196.85 0)
      (effects (font (size 1.27 1.27) (thickness 0.15)) (justify left bottom) hide)
    )
    (property "Tolerance" "~" (at 34.29 196.85 0)
      (effects (font (size 1.27 1.27)) (justify left bottom) hide)
    )
    (property "Current" "1A" (at 13.97 196.85 0)
      (effects (font (size 1.27 1.27) (thickness 0.15)) (justify left bottom) hide)
    )
    (pin "1")
    (pin "2")
    (instances
      (project "d1600e-psu-breakout-board"
        (path ""
          (reference "R17") (unit 1)
        )
      )
    )
  )

  (symbol (lib_id "antmicroResistors0402:R_0R_0402") (at 29.21 194.31 270) (unit 1)
    (in_bom yes) (on_board yes) (dnp no)
    (property "Reference" "R14" (at 30.48 195.58 90)
      (effects (font (size 1.27 1.27)) (justify left))
    )
    (property "Value" "R_0R_0402" (at 25.4 194.31 0)
      (effects (font (size 1.27 1.27)) hide)
    )
    (property "Footprint" "antmicro-footprints:R_0402_1005Metric" (at 13.97 214.63 0)
      (effects (font (size 1.27 1.27) (thickness 0.15)) (justify left bottom) hide)
    )
    (property "Datasheet" "https://industrial.panasonic.com/cdbs/www-data/pdf/RDA0000/AOA0000C301.pdf" (at 11.43 214.63 0)
      (effects (font (size 1.27 1.27) (thickness 0.15)) (justify left bottom) hide)
    )
    (property "Manufacturer" "Panasonic" (at 6.35 214.63 0)
      (effects (font (size 1.27 1.27) (thickness 0.15)) (justify left bottom) hide)
    )
    (property "MPN" "ERJ2GE0R00X" (at 8.89 214.63 0)
      (effects (font (size 1.27 1.27) (thickness 0.15)) (justify left bottom) hide)
    )
    (property "Val" "0R" (at 30.48 198.12 90)
      (effects (font (size 1.27 1.27) (thickness 0.15)) (justify left))
    )
    (property "License" "Apache-2.0" (at 3.81 214.63 0)
      (effects (font (size 1.27 1.27) (thickness 0.15)) (justify left bottom) hide)
    )
    (property "Author" "Antmicro" (at 1.27 214.63 0)
      (effects (font (size 1.27 1.27) (thickness 0.15)) (justify left bottom) hide)
    )
    (property "Tolerance" "~" (at 19.05 214.63 0)
      (effects (font (size 1.27 1.27)) (justify left bottom) hide)
    )
    (property "Current" "1A" (at -1.27 214.63 0)
      (effects (font (size 1.27 1.27) (thickness 0.15)) (justify left bottom) hide)
    )
    (pin "1")
    (pin "2")
    (instances
      (project "d1600e-psu-breakout-board"
        (path ""
          (reference "R14") (unit 1)
        )
      )
    )
  )

  (symbol (lib_id "antmicroResistors0402:R_0R_0402") (at 36.83 194.31 270) (unit 1)
    (in_bom yes) (on_board yes) (dnp no)
    (property "Reference" "R16" (at 38.1 195.58 90)
      (effects (font (size 1.27 1.27)) (justify left))
    )
    (property "Value" "R_0R_0402" (at 33.02 194.31 0)
      (effects (font (size 1.27 1.27)) hide)
    )
    (property "Footprint" "antmicro-footprints:R_0402_1005Metric" (at 21.59 214.63 0)
      (effects (font (size 1.27 1.27) (thickness 0.15)) (justify left bottom) hide)
    )
    (property "Datasheet" "https://industrial.panasonic.com/cdbs/www-data/pdf/RDA0000/AOA0000C301.pdf" (at 19.05 214.63 0)
      (effects (font (size 1.27 1.27) (thickness 0.15)) (justify left bottom) hide)
    )
    (property "Manufacturer" "Panasonic" (at 13.97 214.63 0)
      (effects (font (size 1.27 1.27) (thickness 0.15)) (justify left bottom) hide)
    )
    (property "MPN" "ERJ2GE0R00X" (at 16.51 214.63 0)
      (effects (font (size 1.27 1.27) (thickness 0.15)) (justify left bottom) hide)
    )
    (property "Val" "0R" (at 38.1 198.12 90)
      (effects (font (size 1.27 1.27) (thickness 0.15)) (justify left))
    )
    (property "License" "Apache-2.0" (at 11.43 214.63 0)
      (effects (font (size 1.27 1.27) (thickness 0.15)) (justify left bottom) hide)
    )
    (property "Author" "Antmicro" (at 8.89 214.63 0)
      (effects (font (size 1.27 1.27) (thickness 0.15)) (justify left bottom) hide)
    )
    (property "Tolerance" "~" (at 26.67 214.63 0)
      (effects (font (size 1.27 1.27)) (justify left bottom) hide)
    )
    (property "Current" "1A" (at 6.35 214.63 0)
      (effects (font (size 1.27 1.27) (thickness 0.15)) (justify left bottom) hide)
    )
    (pin "1")
    (pin "2")
    (instances
      (project "d1600e-psu-breakout-board"
        (path ""
          (reference "R16") (unit 1)
        )
      )
    )
  )

  (symbol (lib_id "antmicroResistors0402:R_0R_0402") (at 44.45 194.31 270) (unit 1)
    (in_bom yes) (on_board yes) (dnp no)
    (property "Reference" "R18" (at 45.72 195.58 90)
      (effects (font (size 1.27 1.27)) (justify left))
    )
    (property "Value" "R_0R_0402" (at 40.64 194.31 0)
      (effects (font (size 1.27 1.27)) hide)
    )
    (property "Footprint" "antmicro-footprints:R_0402_1005Metric" (at 29.21 214.63 0)
      (effects (font (size 1.27 1.27) (thickness 0.15)) (justify left bottom) hide)
    )
    (property "Datasheet" "https://industrial.panasonic.com/cdbs/www-data/pdf/RDA0000/AOA0000C301.pdf" (at 26.67 214.63 0)
      (effects (font (size 1.27 1.27) (thickness 0.15)) (justify left bottom) hide)
    )
    (property "Manufacturer" "Panasonic" (at 21.59 214.63 0)
      (effects (font (size 1.27 1.27) (thickness 0.15)) (justify left bottom) hide)
    )
    (property "MPN" "ERJ2GE0R00X" (at 24.13 214.63 0)
      (effects (font (size 1.27 1.27) (thickness 0.15)) (justify left bottom) hide)
    )
    (property "Val" "0R" (at 45.72 198.12 90)
      (effects (font (size 1.27 1.27) (thickness 0.15)) (justify left))
    )
    (property "License" "Apache-2.0" (at 19.05 214.63 0)
      (effects (font (size 1.27 1.27) (thickness 0.15)) (justify left bottom) hide)
    )
    (property "Author" "Antmicro" (at 16.51 214.63 0)
      (effects (font (size 1.27 1.27) (thickness 0.15)) (justify left bottom) hide)
    )
    (property "Tolerance" "~" (at 34.29 214.63 0)
      (effects (font (size 1.27 1.27)) (justify left bottom) hide)
    )
    (property "Current" "1A" (at 13.97 214.63 0)
      (effects (font (size 1.27 1.27) (thickness 0.15)) (justify left bottom) hide)
    )
    (pin "1")
    (pin "2")
    (instances
      (project "d1600e-psu-breakout-board"
        (path ""
          (reference "R18") (unit 1)
        )
      )
    )
  )

  (symbol (lib_id "antmicropower:GND") (at 29.21 201.93 0) (unit 1)
    (in_bom yes) (on_board yes) (dnp no)
    (property "Reference" "#PWR041" (at 29.21 208.28 0)
      (effects (font (size 1.27 1.27)) hide)
    )
    (property "Value" "GND" (at 29.21 205.74 0)
      (effects (font (size 1.27 1.27) (thickness 0.15)))
    )
    (property "Footprint" "" (at 38.1 209.55 0)
      (effects (font (size 1.27 1.27) (thickness 0.15)) (justify left bottom) hide)
    )
    (property "Datasheet" "" (at 38.1 214.63 0)
      (effects (font (size 1.27 1.27) (thickness 0.15)) (justify left bottom) hide)
    )
    (property "Author" "Antmicro" (at 38.1 209.55 0)
      (effects (font (size 1.27 1.27) (thickness 0.15)) (justify left bottom) hide)
    )
    (property "License" "Apache-2.0" (at 38.1 212.09 0)
      (effects (font (size 1.27 1.27) (thickness 0.15)) (justify left bottom) hide)
    )
    (pin "1")
    (instances
      (project "d1600e-psu-breakout-board"
        (path ""
          (reference "#PWR041") (unit 1)
        )
      )
    )
  )

  (symbol (lib_id "antmicropower:GND") (at 36.83 201.93 0) (unit 1)
    (in_bom yes) (on_board yes) (dnp no)
    (property "Reference" "#PWR042" (at 36.83 208.28 0)
      (effects (font (size 1.27 1.27)) hide)
    )
    (property "Value" "GND" (at 36.83 205.74 0)
      (effects (font (size 1.27 1.27) (thickness 0.15)))
    )
    (property "Footprint" "" (at 45.72 209.55 0)
      (effects (font (size 1.27 1.27) (thickness 0.15)) (justify left bottom) hide)
    )
    (property "Datasheet" "" (at 45.72 214.63 0)
      (effects (font (size 1.27 1.27) (thickness 0.15)) (justify left bottom) hide)
    )
    (property "Author" "Antmicro" (at 45.72 209.55 0)
      (effects (font (size 1.27 1.27) (thickness 0.15)) (justify left bottom) hide)
    )
    (property "License" "Apache-2.0" (at 45.72 212.09 0)
      (effects (font (size 1.27 1.27) (thickness 0.15)) (justify left bottom) hide)
    )
    (pin "1")
    (instances
      (project "d1600e-psu-breakout-board"
        (path ""
          (reference "#PWR042") (unit 1)
        )
      )
    )
  )

  (symbol (lib_id "antmicropower:GND") (at 44.45 201.93 0) (unit 1)
    (in_bom yes) (on_board yes) (dnp no)
    (property "Reference" "#PWR043" (at 44.45 208.28 0)
      (effects (font (size 1.27 1.27)) hide)
    )
    (property "Value" "GND" (at 44.45 205.74 0)
      (effects (font (size 1.27 1.27) (thickness 0.15)))
    )
    (property "Footprint" "" (at 53.34 209.55 0)
      (effects (font (size 1.27 1.27) (thickness 0.15)) (justify left bottom) hide)
    )
    (property "Datasheet" "" (at 53.34 214.63 0)
      (effects (font (size 1.27 1.27) (thickness 0.15)) (justify left bottom) hide)
    )
    (property "Author" "Antmicro" (at 53.34 209.55 0)
      (effects (font (size 1.27 1.27) (thickness 0.15)) (justify left bottom) hide)
    )
    (property "License" "Apache-2.0" (at 53.34 212.09 0)
      (effects (font (size 1.27 1.27) (thickness 0.15)) (justify left bottom) hide)
    )
    (pin "1")
    (instances
      (project "d1600e-psu-breakout-board"
        (path ""
          (reference "#PWR043") (unit 1)
        )
      )
    )
  )

  (symbol (lib_id "antmicropower:GND") (at 72.39 201.93 0) (unit 1)
    (in_bom yes) (on_board yes) (dnp no)
    (property "Reference" "#PWR046" (at 72.39 208.28 0)
      (effects (font (size 1.27 1.27)) hide)
    )
    (property "Value" "GND" (at 72.39 205.74 0)
      (effects (font (size 1.27 1.27) (thickness 0.15)))
    )
    (property "Footprint" "" (at 81.28 209.55 0)
      (effects (font (size 1.27 1.27) (thickness 0.15)) (justify left bottom) hide)
    )
    (property "Datasheet" "" (at 81.28 214.63 0)
      (effects (font (size 1.27 1.27) (thickness 0.15)) (justify left bottom) hide)
    )
    (property "Author" "Antmicro" (at 81.28 209.55 0)
      (effects (font (size 1.27 1.27) (thickness 0.15)) (justify left bottom) hide)
    )
    (property "License" "Apache-2.0" (at 81.28 212.09 0)
      (effects (font (size 1.27 1.27) (thickness 0.15)) (justify left bottom) hide)
    )
    (pin "1")
    (instances
      (project "d1600e-psu-breakout-board"
        (path ""
          (reference "#PWR046") (unit 1)
        )
      )
    )
  )

  (symbol (lib_id "antmicroTestPoints:TP_1mm_SMD") (at 138.43 193.04 0) (unit 1)
    (in_bom no) (on_board yes) (dnp no) (fields_autoplaced)
    (property "Reference" "TP_PC1" (at 143.51 193.04 0)
      (effects (font (size 1.27 1.27)) (justify left))
    )
    (property "Value" "TP_1mm_SMD" (at 153.67 200.66 0)
      (effects (font (size 1.27 1.27) (thickness 0.15)) (justify left bottom) hide)
    )
    (property "Footprint" "antmicro-footprints:TP_SMD_1mm" (at 153.67 203.2 0)
      (effects (font (size 1.27 1.27) (thickness 0.15)) (justify left bottom) hide)
    )
    (property "Datasheet" "" (at 156.21 205.74 0)
      (effects (font (size 1.27 1.27) (thickness 0.15)) (justify left bottom) hide)
    )
    (property "MPN" "" (at 138.43 193.04 0)
      (effects (font (size 1.27 1.27)) hide)
    )
    (property "Manufacturer" "" (at 138.43 193.04 0)
      (effects (font (size 1.27 1.27)) hide)
    )
    (property "Author" "Antmicro" (at 153.67 208.28 0)
      (effects (font (size 1.27 1.27) (thickness 0.15)) (justify left bottom) hide)
    )
    (property "License" "Apache-2.0" (at 153.67 210.82 0)
      (effects (font (size 1.27 1.27) (thickness 0.15)) (justify left bottom) hide)
    )
    (pin "1")
    (instances
      (project "d1600e-psu-breakout-board"
        (path ""
          (reference "TP_PC1") (unit 1)
        )
      )
    )
  )

  (symbol (lib_name "TMCS1100A2-Q1_1") (lib_id "antmicroPowerMeasurement:TMCS1100A2-Q1") (at 34.29 48.26 0) (unit 1)
    (in_bom yes) (on_board yes) (dnp no)
    (property "Reference" "U8" (at 43.18 41.91 0)
      (effects (font (size 1.27 1.27)))
    )
    (property "Value" "TMCS1100A2-Q1" (at 67.31 55.88 0)
      (effects (font (size 1.27 1.27) (thickness 0.15)) (justify left bottom) hide)
    )
    (property "Footprint" "antmicro-footprints:SOIC-8_3.9x4.9x1.75mm_P1.27mm" (at 67.31 58.42 0)
      (effects (font (size 1.27 1.27) (thickness 0.15)) (justify left bottom) hide)
    )
    (property "Datasheet" "https://www.ti.com/lit/ds/symlink/tmcs1100-q1.pdf?ts=1647195769204&ref_url=https%253A%252F%252Fwww.mouser.de%252F" (at 67.31 60.96 0)
      (effects (font (size 1.27 1.27) (thickness 0.15)) (justify left bottom) hide)
    )
    (property "MPN" "TMCS1100A2QDRQ1" (at 43.18 44.45 0)
      (effects (font (size 1.27 1.27) (thickness 0.15)))
    )
    (property "Manufacturer" "Texas Instruments" (at 67.31 63.5 0)
      (effects (font (size 1.27 1.27) (thickness 0.15)) (justify left bottom) hide)
    )
    (property "Author" "Antmicro" (at 67.31 66.04 0)
      (effects (font (size 1.27 1.27) (thickness 0.15)) (justify left bottom) hide)
    )
    (property "License" "Apache-2.0" (at 67.31 68.58 0)
      (effects (font (size 1.27 1.27) (thickness 0.15)) (justify left bottom) hide)
    )
    (pin "1")
    (pin "2")
    (pin "3")
    (pin "4")
    (pin "5")
    (pin "6")
    (pin "7")
    (pin "8")
    (instances
      (project "d1600e-psu-breakout-board"
        (path ""
          (reference "U8") (unit 1)
        )
      )
    )
  )

  (symbol (lib_id "antmicroTestPoints:TP_1mm_SMD") (at 138.43 195.58 0) (unit 1)
    (in_bom no) (on_board yes) (dnp no) (fields_autoplaced)
    (property "Reference" "TP_PC2" (at 143.51 195.58 0)
      (effects (font (size 1.27 1.27)) (justify left))
    )
    (property "Value" "TP_1mm_SMD" (at 153.67 203.2 0)
      (effects (font (size 1.27 1.27) (thickness 0.15)) (justify left bottom) hide)
    )
    (property "Footprint" "antmicro-footprints:TP_SMD_1mm" (at 153.67 205.74 0)
      (effects (font (size 1.27 1.27) (thickness 0.15)) (justify left bottom) hide)
    )
    (property "Datasheet" "" (at 156.21 208.28 0)
      (effects (font (size 1.27 1.27) (thickness 0.15)) (justify left bottom) hide)
    )
    (property "MPN" "" (at 138.43 195.58 0)
      (effects (font (size 1.27 1.27)) hide)
    )
    (property "Manufacturer" "" (at 138.43 195.58 0)
      (effects (font (size 1.27 1.27)) hide)
    )
    (property "Author" "Antmicro" (at 153.67 210.82 0)
      (effects (font (size 1.27 1.27) (thickness 0.15)) (justify left bottom) hide)
    )
    (property "License" "Apache-2.0" (at 153.67 213.36 0)
      (effects (font (size 1.27 1.27) (thickness 0.15)) (justify left bottom) hide)
    )
    (pin "1")
    (instances
      (project "d1600e-psu-breakout-board"
        (path ""
          (reference "TP_PC2") (unit 1)
        )
      )
    )
  )

  (symbol (lib_id "antmicroTestPoints:TP_1mm_SMD") (at 138.43 198.12 0) (unit 1)
    (in_bom no) (on_board yes) (dnp no) (fields_autoplaced)
    (property "Reference" "TP_PC3" (at 143.51 198.12 0)
      (effects (font (size 1.27 1.27)) (justify left))
    )
    (property "Value" "TP_1mm_SMD" (at 153.67 205.74 0)
      (effects (font (size 1.27 1.27) (thickness 0.15)) (justify left bottom) hide)
    )
    (property "Footprint" "antmicro-footprints:TP_SMD_1mm" (at 153.67 208.28 0)
      (effects (font (size 1.27 1.27) (thickness 0.15)) (justify left bottom) hide)
    )
    (property "Datasheet" "" (at 156.21 210.82 0)
      (effects (font (size 1.27 1.27) (thickness 0.15)) (justify left bottom) hide)
    )
    (property "MPN" "" (at 138.43 198.12 0)
      (effects (font (size 1.27 1.27)) hide)
    )
    (property "Manufacturer" "" (at 138.43 198.12 0)
      (effects (font (size 1.27 1.27)) hide)
    )
    (property "Author" "Antmicro" (at 153.67 213.36 0)
      (effects (font (size 1.27 1.27) (thickness 0.15)) (justify left bottom) hide)
    )
    (property "License" "Apache-2.0" (at 153.67 215.9 0)
      (effects (font (size 1.27 1.27) (thickness 0.15)) (justify left bottom) hide)
    )
    (pin "1")
    (instances
      (project "d1600e-psu-breakout-board"
        (path ""
          (reference "TP_PC3") (unit 1)
        )
      )
    )
  )

  (symbol (lib_id "antmicroTestPoints:TP_1mm_SMD") (at 138.43 200.66 0) (unit 1)
    (in_bom no) (on_board yes) (dnp no) (fields_autoplaced)
    (property "Reference" "TP_PC4" (at 143.51 200.66 0)
      (effects (font (size 1.27 1.27)) (justify left))
    )
    (property "Value" "TP_1mm_SMD" (at 153.67 208.28 0)
      (effects (font (size 1.27 1.27) (thickness 0.15)) (justify left bottom) hide)
    )
    (property "Footprint" "antmicro-footprints:TP_SMD_1mm" (at 153.67 210.82 0)
      (effects (font (size 1.27 1.27) (thickness 0.15)) (justify left bottom) hide)
    )
    (property "Datasheet" "" (at 156.21 213.36 0)
      (effects (font (size 1.27 1.27) (thickness 0.15)) (justify left bottom) hide)
    )
    (property "MPN" "" (at 138.43 200.66 0)
      (effects (font (size 1.27 1.27)) hide)
    )
    (property "Manufacturer" "" (at 138.43 200.66 0)
      (effects (font (size 1.27 1.27)) hide)
    )
    (property "Author" "Antmicro" (at 153.67 215.9 0)
      (effects (font (size 1.27 1.27) (thickness 0.15)) (justify left bottom) hide)
    )
    (property "License" "Apache-2.0" (at 153.67 218.44 0)
      (effects (font (size 1.27 1.27) (thickness 0.15)) (justify left bottom) hide)
    )
    (pin "1")
    (instances
      (project "d1600e-psu-breakout-board"
        (path ""
          (reference "TP_PC4") (unit 1)
        )
      )
    )
  )

  (symbol (lib_id "antmicroTestPoints:TP_1mm_SMD") (at 138.43 203.2 0) (unit 1)
    (in_bom no) (on_board yes) (dnp no) (fields_autoplaced)
    (property "Reference" "TP_PC5" (at 143.51 203.2 0)
      (effects (font (size 1.27 1.27)) (justify left))
    )
    (property "Value" "TP_1mm_SMD" (at 153.67 210.82 0)
      (effects (font (size 1.27 1.27) (thickness 0.15)) (justify left bottom) hide)
    )
    (property "Footprint" "antmicro-footprints:TP_SMD_1mm" (at 153.67 213.36 0)
      (effects (font (size 1.27 1.27) (thickness 0.15)) (justify left bottom) hide)
    )
    (property "Datasheet" "" (at 156.21 215.9 0)
      (effects (font (size 1.27 1.27) (thickness 0.15)) (justify left bottom) hide)
    )
    (property "MPN" "" (at 138.43 203.2 0)
      (effects (font (size 1.27 1.27)) hide)
    )
    (property "Manufacturer" "" (at 138.43 203.2 0)
      (effects (font (size 1.27 1.27)) hide)
    )
    (property "Author" "Antmicro" (at 153.67 218.44 0)
      (effects (font (size 1.27 1.27) (thickness 0.15)) (justify left bottom) hide)
    )
    (property "License" "Apache-2.0" (at 153.67 220.98 0)
      (effects (font (size 1.27 1.27) (thickness 0.15)) (justify left bottom) hide)
    )
    (pin "1")
    (instances
      (project "d1600e-psu-breakout-board"
        (path ""
          (reference "TP_PC5") (unit 1)
        )
      )
    )
  )

  (symbol (lib_id "antmicroResistors0402:R_4k7_0402") (at 53.34 176.53 270) (unit 1)
    (in_bom yes) (on_board yes) (dnp no)
    (property "Reference" "R19" (at 54.61 177.8 90)
      (effects (font (size 1.27 1.27)) (justify left))
    )
    (property "Value" "R_4k7_0402" (at 40.64 196.85 0)
      (effects (font (size 1.27 1.27) (thickness 0.15)) (justify left bottom) hide)
    )
    (property "Footprint" "antmicro-footprints:R_0402_1005Metric" (at 38.1 196.85 0)
      (effects (font (size 1.27 1.27) (thickness 0.15)) (justify left bottom) hide)
    )
    (property "Datasheet" "https://www.bourns.com/docs/product-datasheets/cr.pdf" (at 35.56 196.85 0)
      (effects (font (size 1.27 1.27) (thickness 0.15)) (justify left bottom) hide)
    )
    (property "Manufacturer" "Bourns" (at 30.48 196.85 0)
      (effects (font (size 1.27 1.27) (thickness 0.15)) (justify left bottom) hide)
    )
    (property "MPN" "CR0402-FX-4701GLF" (at 33.02 196.85 0)
      (effects (font (size 1.27 1.27) (thickness 0.15)) (justify left bottom) hide)
    )
    (property "Val" "4k7" (at 54.61 180.34 90)
      (effects (font (size 1.27 1.27) (thickness 0.15)) (justify left))
    )
    (property "License" "Apache-2.0" (at 27.94 196.85 0)
      (effects (font (size 1.27 1.27) (thickness 0.15)) (justify left bottom) hide)
    )
    (property "Author" "Antmicro" (at 25.4 196.85 0)
      (effects (font (size 1.27 1.27) (thickness 0.15)) (justify left bottom) hide)
    )
    (property "Tolerance" "1%" (at 43.18 196.85 0)
      (effects (font (size 1.27 1.27)) (justify left bottom) hide)
    )
    (pin "1")
    (pin "2")
    (instances
      (project "d1600e-psu-breakout-board"
        (path ""
          (reference "R19") (unit 1)
        )
      )
    )
  )

  (symbol (lib_id "antmicropower:GND") (at 54.61 55.88 0) (unit 1)
    (in_bom yes) (on_board yes) (dnp no)
    (property "Reference" "#PWR044" (at 54.61 62.23 0)
      (effects (font (size 1.27 1.27)) hide)
    )
    (property "Value" "GND" (at 54.61 59.69 0)
      (effects (font (size 1.27 1.27) (thickness 0.15)))
    )
    (property "Footprint" "" (at 63.5 63.5 0)
      (effects (font (size 1.27 1.27) (thickness 0.15)) (justify left bottom) hide)
    )
    (property "Datasheet" "" (at 63.5 68.58 0)
      (effects (font (size 1.27 1.27) (thickness 0.15)) (justify left bottom) hide)
    )
    (property "Author" "Antmicro" (at 63.5 63.5 0)
      (effects (font (size 1.27 1.27) (thickness 0.15)) (justify left bottom) hide)
    )
    (property "License" "Apache-2.0" (at 63.5 66.04 0)
      (effects (font (size 1.27 1.27) (thickness 0.15)) (justify left bottom) hide)
    )
    (pin "1")
    (instances
      (project "d1600e-psu-breakout-board"
        (path ""
          (reference "#PWR044") (unit 1)
        )
      )
    )
  )

  (symbol (lib_id "antmicroDataAcquisitionAnalogtoDigitalConvertersADC:ADS7828") (at 287.02 52.07 0) (unit 1)
    (in_bom yes) (on_board yes) (dnp no) (fields_autoplaced)
    (property "Reference" "U14" (at 295.91 44.45 0)
      (effects (font (size 1.27 1.27)))
    )
    (property "Value" "ADS7828" (at 318.77 57.15 0)
      (effects (font (size 1.27 1.27) (thickness 0.15)) (justify left bottom) hide)
    )
    (property "Footprint" "antmicro-footprints:TSSOP-16_4.4x5mm_P0.65mm" (at 318.77 59.69 0)
      (effects (font (size 1.27 1.27) (thickness 0.15)) (justify left bottom) hide)
    )
    (property "Datasheet" "http://www.ti.com/lit/ds/symlink/ads7828.pdf" (at 318.77 62.23 0)
      (effects (font (size 1.27 1.27) (thickness 0.15)) (justify left bottom) hide)
    )
    (property "MPN" "ADS7828E/250" (at 295.91 46.99 0)
      (effects (font (size 1.27 1.27) (thickness 0.15)))
    )
    (property "Manufacturer" "Texas Instruments" (at 318.77 64.77 0)
      (effects (font (size 1.27 1.27) (thickness 0.15)) (justify left bottom) hide)
    )
    (property "Author" "Antmicro" (at 318.77 67.31 0)
      (effects (font (size 1.27 1.27) (thickness 0.15)) (justify left bottom) hide)
    )
    (property "License" "Apache-2.0" (at 318.77 69.85 0)
      (effects (font (size 1.27 1.27) (thickness 0.15)) (justify left bottom) hide)
    )
    (pin "1")
    (pin "10")
    (pin "11")
    (pin "12")
    (pin "13")
    (pin "14")
    (pin "15")
    (pin "16")
    (pin "2")
    (pin "3")
    (pin "4")
    (pin "5")
    (pin "6")
    (pin "7")
    (pin "8")
    (pin "9")
    (instances
      (project "d1600e-psu-breakout-board"
        (path ""
          (reference "U14") (unit 1)
        )
      )
    )
  )

  (symbol (lib_name "C_100n_0402_1") (lib_id "antmicroCapacitors0402:C_100n_0402") (at 40.64 36.83 0) (mirror x) (unit 1)
    (in_bom yes) (on_board yes) (dnp no)
    (property "Reference" "C28" (at 46.99 35.56 0)
      (effects (font (size 1.27 1.27)))
    )
    (property "Value" "C_100n_0402" (at 60.96 26.67 0)
      (effects (font (size 1.27 1.27) (thickness 0.15)) (justify left bottom) hide)
    )
    (property "Footprint" "antmicro-footprints:C_0402_1005Metric" (at 60.96 24.13 0)
      (effects (font (size 1.27 1.27) (thickness 0.15)) (justify left bottom) hide)
    )
    (property "Datasheet" "https://www.murata.com/products/productdetail?partno=GRM155R61H104KE14%23" (at 60.96 21.59 0)
      (effects (font (size 1.27 1.27) (thickness 0.15)) (justify left bottom) hide)
    )
    (property "Manufacturer" "Murata" (at 60.96 16.51 0)
      (effects (font (size 1.27 1.27) (thickness 0.15)) (justify left bottom) hide)
    )
    (property "MPN" "GRM155R61H104KE14D" (at 60.96 19.05 0)
      (effects (font (size 1.27 1.27) (thickness 0.15)) (justify left bottom) hide)
    )
    (property "Val" "100n" (at 39.37 35.56 0)
      (effects (font (size 1.27 1.27) (thickness 0.15)))
    )
    (property "License" "Apache-2.0" (at 60.96 13.97 0)
      (effects (font (size 1.27 1.27) (thickness 0.15)) (justify left bottom) hide)
    )
    (property "Author" "Antmicro" (at 60.96 11.43 0)
      (effects (font (size 1.27 1.27) (thickness 0.15)) (justify left bottom) hide)
    )
    (property "Voltage" "50V" (at 60.96 8.89 0)
      (effects (font (size 1.27 1.27)) (justify left bottom) hide)
    )
    (property "Dielectric" "X5R" (at 60.96 6.35 0)
      (effects (font (size 1.27 1.27)) (justify left bottom) hide)
    )
    (pin "1")
    (pin "2")
    (instances
      (project "d1600e-psu-breakout-board"
        (path ""
          (reference "C28") (unit 1)
        )
      )
    )
  )

  (symbol (lib_id "antmicropower:GND") (at 307.34 85.09 0) (unit 1)
    (in_bom yes) (on_board yes) (dnp no)
    (property "Reference" "#PWR055" (at 307.34 91.44 0)
      (effects (font (size 1.27 1.27)) hide)
    )
    (property "Value" "GND" (at 307.34 88.9 0)
      (effects (font (size 1.27 1.27) (thickness 0.15)))
    )
    (property "Footprint" "" (at 316.23 92.71 0)
      (effects (font (size 1.27 1.27) (thickness 0.15)) (justify left bottom) hide)
    )
    (property "Datasheet" "" (at 316.23 97.79 0)
      (effects (font (size 1.27 1.27) (thickness 0.15)) (justify left bottom) hide)
    )
    (property "Author" "Antmicro" (at 316.23 92.71 0)
      (effects (font (size 1.27 1.27) (thickness 0.15)) (justify left bottom) hide)
    )
    (property "License" "Apache-2.0" (at 316.23 95.25 0)
      (effects (font (size 1.27 1.27) (thickness 0.15)) (justify left bottom) hide)
    )
    (pin "1")
    (instances
      (project "d1600e-psu-breakout-board"
        (path ""
          (reference "#PWR055") (unit 1)
        )
      )
    )
  )

  (symbol (lib_name "R_0R_0402_1") (lib_id "antmicroResistors0402:R_0R_0402") (at 336.55 77.47 270) (unit 1)
    (in_bom yes) (on_board yes) (dnp no)
    (property "Reference" "R31" (at 337.82 78.74 90)
      (effects (font (size 1.27 1.27)) (justify left))
    )
    (property "Value" "R_0R_0402" (at 323.85 97.79 0)
      (effects (font (size 1.27 1.27) (thickness 0.15)) (justify left bottom) hide)
    )
    (property "Footprint" "antmicro-footprints:R_0402_1005Metric" (at 321.31 97.79 0)
      (effects (font (size 1.27 1.27) (thickness 0.15)) (justify left bottom) hide)
    )
    (property "Datasheet" "https://industrial.panasonic.com/cdbs/www-data/pdf/RDA0000/AOA0000C301.pdf" (at 318.77 97.79 0)
      (effects (font (size 1.27 1.27) (thickness 0.15)) (justify left bottom) hide)
    )
    (property "Manufacturer" "Panasonic" (at 313.69 97.79 0)
      (effects (font (size 1.27 1.27) (thickness 0.15)) (justify left bottom) hide)
    )
    (property "MPN" "ERJ2GE0R00X" (at 316.23 97.79 0)
      (effects (font (size 1.27 1.27) (thickness 0.15)) (justify left bottom) hide)
    )
    (property "Val" "0R" (at 337.82 81.28 90)
      (effects (font (size 1.27 1.27) (thickness 0.15)) (justify left))
    )
    (property "License" "Apache-2.0" (at 311.15 97.79 0)
      (effects (font (size 1.27 1.27) (thickness 0.15)) (justify left bottom) hide)
    )
    (property "Author" "Antmicro" (at 308.61 97.79 0)
      (effects (font (size 1.27 1.27) (thickness 0.15)) (justify left bottom) hide)
    )
    (property "Tolerance" "~" (at 326.39 97.79 0)
      (effects (font (size 1.27 1.27)) (justify left bottom) hide)
    )
    (property "Current" "1A" (at 306.07 97.79 0)
      (effects (font (size 1.27 1.27) (thickness 0.15)) (justify left bottom) hide)
    )
    (pin "1")
    (pin "2")
    (instances
      (project "d1600e-psu-breakout-board"
        (path ""
          (reference "R31") (unit 1)
        )
      )
    )
  )

  (symbol (lib_name "R_0R_0402_2") (lib_id "antmicroResistors0402:R_0R_0402") (at 345.44 77.47 270) (unit 1)
    (in_bom yes) (on_board yes) (dnp no)
    (property "Reference" "R33" (at 346.71 78.74 90)
      (effects (font (size 1.27 1.27)) (justify left))
    )
    (property "Value" "R_0R_0402" (at 332.74 97.79 0)
      (effects (font (size 1.27 1.27) (thickness 0.15)) (justify left bottom) hide)
    )
    (property "Footprint" "antmicro-footprints:R_0402_1005Metric" (at 330.2 97.79 0)
      (effects (font (size 1.27 1.27) (thickness 0.15)) (justify left bottom) hide)
    )
    (property "Datasheet" "https://industrial.panasonic.com/cdbs/www-data/pdf/RDA0000/AOA0000C301.pdf" (at 327.66 97.79 0)
      (effects (font (size 1.27 1.27) (thickness 0.15)) (justify left bottom) hide)
    )
    (property "Manufacturer" "Panasonic" (at 322.58 97.79 0)
      (effects (font (size 1.27 1.27) (thickness 0.15)) (justify left bottom) hide)
    )
    (property "MPN" "ERJ2GE0R00X" (at 325.12 97.79 0)
      (effects (font (size 1.27 1.27) (thickness 0.15)) (justify left bottom) hide)
    )
    (property "Val" "0R" (at 346.71 81.28 90)
      (effects (font (size 1.27 1.27) (thickness 0.15)) (justify left))
    )
    (property "License" "Apache-2.0" (at 320.04 97.79 0)
      (effects (font (size 1.27 1.27) (thickness 0.15)) (justify left bottom) hide)
    )
    (property "Author" "Antmicro" (at 317.5 97.79 0)
      (effects (font (size 1.27 1.27) (thickness 0.15)) (justify left bottom) hide)
    )
    (property "Tolerance" "~" (at 335.28 97.79 0)
      (effects (font (size 1.27 1.27)) (justify left bottom) hide)
    )
    (property "Current" "1A" (at 314.96 97.79 0)
      (effects (font (size 1.27 1.27) (thickness 0.15)) (justify left bottom) hide)
    )
    (pin "1")
    (pin "2")
    (instances
      (project "d1600e-psu-breakout-board"
        (path ""
          (reference "R33") (unit 1)
        )
      )
    )
  )

  (symbol (lib_id "antmicropower:GND") (at 336.55 85.09 0) (unit 1)
    (in_bom yes) (on_board yes) (dnp no)
    (property "Reference" "#PWR056" (at 336.55 91.44 0)
      (effects (font (size 1.27 1.27)) hide)
    )
    (property "Value" "GND" (at 336.55 88.9 0)
      (effects (font (size 1.27 1.27) (thickness 0.15)))
    )
    (property "Footprint" "" (at 345.44 92.71 0)
      (effects (font (size 1.27 1.27) (thickness 0.15)) (justify left bottom) hide)
    )
    (property "Datasheet" "" (at 345.44 97.79 0)
      (effects (font (size 1.27 1.27) (thickness 0.15)) (justify left bottom) hide)
    )
    (property "Author" "Antmicro" (at 345.44 92.71 0)
      (effects (font (size 1.27 1.27) (thickness 0.15)) (justify left bottom) hide)
    )
    (property "License" "Apache-2.0" (at 345.44 95.25 0)
      (effects (font (size 1.27 1.27) (thickness 0.15)) (justify left bottom) hide)
    )
    (pin "1")
    (instances
      (project "d1600e-psu-breakout-board"
        (path ""
          (reference "#PWR056") (unit 1)
        )
      )
    )
  )

  (symbol (lib_id "antmicropower:GND") (at 345.44 85.09 0) (unit 1)
    (in_bom yes) (on_board yes) (dnp no)
    (property "Reference" "#PWR057" (at 345.44 91.44 0)
      (effects (font (size 1.27 1.27)) hide)
    )
    (property "Value" "GND" (at 345.44 88.9 0)
      (effects (font (size 1.27 1.27) (thickness 0.15)))
    )
    (property "Footprint" "" (at 354.33 92.71 0)
      (effects (font (size 1.27 1.27) (thickness 0.15)) (justify left bottom) hide)
    )
    (property "Datasheet" "" (at 354.33 97.79 0)
      (effects (font (size 1.27 1.27) (thickness 0.15)) (justify left bottom) hide)
    )
    (property "Author" "Antmicro" (at 354.33 92.71 0)
      (effects (font (size 1.27 1.27) (thickness 0.15)) (justify left bottom) hide)
    )
    (property "License" "Apache-2.0" (at 354.33 95.25 0)
      (effects (font (size 1.27 1.27) (thickness 0.15)) (justify left bottom) hide)
    )
    (pin "1")
    (instances
      (project "d1600e-psu-breakout-board"
        (path ""
          (reference "#PWR057") (unit 1)
        )
      )
    )
  )

  (symbol (lib_id "antmicroTestPoints:TP_1mm_SMD") (at 374.65 59.69 0) (unit 1)
    (in_bom no) (on_board yes) (dnp no) (fields_autoplaced)
    (property "Reference" "TP_ADC1" (at 379.73 59.69 0)
      (effects (font (size 1.27 1.27)) (justify left))
    )
    (property "Value" "TP_1mm_SMD" (at 389.89 67.31 0)
      (effects (font (size 1.27 1.27) (thickness 0.15)) (justify left bottom) hide)
    )
    (property "Footprint" "antmicro-footprints:TP_SMD_1mm" (at 389.89 69.85 0)
      (effects (font (size 1.27 1.27) (thickness 0.15)) (justify left bottom) hide)
    )
    (property "Datasheet" "" (at 392.43 72.39 0)
      (effects (font (size 1.27 1.27) (thickness 0.15)) (justify left bottom) hide)
    )
    (property "MPN" "" (at 374.65 59.69 0)
      (effects (font (size 1.27 1.27)) hide)
    )
    (property "Manufacturer" "" (at 374.65 59.69 0)
      (effects (font (size 1.27 1.27)) hide)
    )
    (property "Author" "Antmicro" (at 389.89 74.93 0)
      (effects (font (size 1.27 1.27) (thickness 0.15)) (justify left bottom) hide)
    )
    (property "License" "Apache-2.0" (at 389.89 77.47 0)
      (effects (font (size 1.27 1.27) (thickness 0.15)) (justify left bottom) hide)
    )
    (pin "1")
    (instances
      (project "d1600e-psu-breakout-board"
        (path ""
          (reference "TP_ADC1") (unit 1)
        )
      )
    )
  )

  (symbol (lib_id "antmicroTestPoints:TP_1mm_SMD") (at 374.65 62.23 0) (unit 1)
    (in_bom no) (on_board yes) (dnp no) (fields_autoplaced)
    (property "Reference" "TP_ADC2" (at 379.73 62.23 0)
      (effects (font (size 1.27 1.27)) (justify left))
    )
    (property "Value" "TP_1mm_SMD" (at 389.89 69.85 0)
      (effects (font (size 1.27 1.27) (thickness 0.15)) (justify left bottom) hide)
    )
    (property "Footprint" "antmicro-footprints:TP_SMD_1mm" (at 389.89 72.39 0)
      (effects (font (size 1.27 1.27) (thickness 0.15)) (justify left bottom) hide)
    )
    (property "Datasheet" "" (at 392.43 74.93 0)
      (effects (font (size 1.27 1.27) (thickness 0.15)) (justify left bottom) hide)
    )
    (property "MPN" "" (at 374.65 62.23 0)
      (effects (font (size 1.27 1.27)) hide)
    )
    (property "Manufacturer" "" (at 374.65 62.23 0)
      (effects (font (size 1.27 1.27)) hide)
    )
    (property "Author" "Antmicro" (at 389.89 77.47 0)
      (effects (font (size 1.27 1.27) (thickness 0.15)) (justify left bottom) hide)
    )
    (property "License" "Apache-2.0" (at 389.89 80.01 0)
      (effects (font (size 1.27 1.27) (thickness 0.15)) (justify left bottom) hide)
    )
    (pin "1")
    (instances
      (project "d1600e-psu-breakout-board"
        (path ""
          (reference "TP_ADC2") (unit 1)
        )
      )
    )
  )

  (symbol (lib_id "antmicroTestPoints:TP_1mm_SMD") (at 374.65 64.77 0) (unit 1)
    (in_bom no) (on_board yes) (dnp no) (fields_autoplaced)
    (property "Reference" "TP_ADC3" (at 379.73 64.77 0)
      (effects (font (size 1.27 1.27)) (justify left))
    )
    (property "Value" "TP_1mm_SMD" (at 389.89 72.39 0)
      (effects (font (size 1.27 1.27) (thickness 0.15)) (justify left bottom) hide)
    )
    (property "Footprint" "antmicro-footprints:TP_SMD_1mm" (at 389.89 74.93 0)
      (effects (font (size 1.27 1.27) (thickness 0.15)) (justify left bottom) hide)
    )
    (property "Datasheet" "" (at 392.43 77.47 0)
      (effects (font (size 1.27 1.27) (thickness 0.15)) (justify left bottom) hide)
    )
    (property "MPN" "" (at 374.65 64.77 0)
      (effects (font (size 1.27 1.27)) hide)
    )
    (property "Manufacturer" "" (at 374.65 64.77 0)
      (effects (font (size 1.27 1.27)) hide)
    )
    (property "Author" "Antmicro" (at 389.89 80.01 0)
      (effects (font (size 1.27 1.27) (thickness 0.15)) (justify left bottom) hide)
    )
    (property "License" "Apache-2.0" (at 389.89 82.55 0)
      (effects (font (size 1.27 1.27) (thickness 0.15)) (justify left bottom) hide)
    )
    (pin "1")
    (instances
      (project "d1600e-psu-breakout-board"
        (path ""
          (reference "TP_ADC3") (unit 1)
        )
      )
    )
  )

  (symbol (lib_id "antmicroTestPoints:TP_1mm_SMD") (at 374.65 67.31 0) (unit 1)
    (in_bom no) (on_board yes) (dnp no) (fields_autoplaced)
    (property "Reference" "TP_ADC4" (at 379.73 67.31 0)
      (effects (font (size 1.27 1.27)) (justify left))
    )
    (property "Value" "TP_1mm_SMD" (at 389.89 74.93 0)
      (effects (font (size 1.27 1.27) (thickness 0.15)) (justify left bottom) hide)
    )
    (property "Footprint" "antmicro-footprints:TP_SMD_1mm" (at 389.89 77.47 0)
      (effects (font (size 1.27 1.27) (thickness 0.15)) (justify left bottom) hide)
    )
    (property "Datasheet" "" (at 392.43 80.01 0)
      (effects (font (size 1.27 1.27) (thickness 0.15)) (justify left bottom) hide)
    )
    (property "MPN" "" (at 374.65 67.31 0)
      (effects (font (size 1.27 1.27)) hide)
    )
    (property "Manufacturer" "" (at 374.65 67.31 0)
      (effects (font (size 1.27 1.27)) hide)
    )
    (property "Author" "Antmicro" (at 389.89 82.55 0)
      (effects (font (size 1.27 1.27) (thickness 0.15)) (justify left bottom) hide)
    )
    (property "License" "Apache-2.0" (at 389.89 85.09 0)
      (effects (font (size 1.27 1.27) (thickness 0.15)) (justify left bottom) hide)
    )
    (pin "1")
    (instances
      (project "d1600e-psu-breakout-board"
        (path ""
          (reference "TP_ADC4") (unit 1)
        )
      )
    )
  )

  (symbol (lib_id "antmicroTestPoints:TP_1mm_SMD") (at 374.65 69.85 0) (unit 1)
    (in_bom no) (on_board yes) (dnp no) (fields_autoplaced)
    (property "Reference" "TP_ADC5" (at 379.73 69.85 0)
      (effects (font (size 1.27 1.27)) (justify left))
    )
    (property "Value" "TP_1mm_SMD" (at 389.89 77.47 0)
      (effects (font (size 1.27 1.27) (thickness 0.15)) (justify left bottom) hide)
    )
    (property "Footprint" "antmicro-footprints:TP_SMD_1mm" (at 389.89 80.01 0)
      (effects (font (size 1.27 1.27) (thickness 0.15)) (justify left bottom) hide)
    )
    (property "Datasheet" "" (at 392.43 82.55 0)
      (effects (font (size 1.27 1.27) (thickness 0.15)) (justify left bottom) hide)
    )
    (property "MPN" "" (at 374.65 69.85 0)
      (effects (font (size 1.27 1.27)) hide)
    )
    (property "Manufacturer" "" (at 374.65 69.85 0)
      (effects (font (size 1.27 1.27)) hide)
    )
    (property "Author" "Antmicro" (at 389.89 85.09 0)
      (effects (font (size 1.27 1.27) (thickness 0.15)) (justify left bottom) hide)
    )
    (property "License" "Apache-2.0" (at 389.89 87.63 0)
      (effects (font (size 1.27 1.27) (thickness 0.15)) (justify left bottom) hide)
    )
    (pin "1")
    (instances
      (project "d1600e-psu-breakout-board"
        (path ""
          (reference "TP_ADC5") (unit 1)
        )
      )
    )
  )

  (symbol (lib_id "antmicroCapacitors0402:C_1u_0402") (at 276.86 44.45 90) (unit 1)
    (in_bom yes) (on_board yes) (dnp no) (fields_autoplaced)
    (property "Reference" "C22" (at 279.4 40.6336 90)
      (effects (font (size 1.27 1.27)) (justify right))
    )
    (property "Value" "C_1u_0402" (at 287.02 24.13 0)
      (effects (font (size 1.27 1.27) (thickness 0.15)) (justify left bottom) hide)
    )
    (property "Footprint" "antmicro-footprints:C_0402_1005Metric" (at 289.56 24.13 0)
      (effects (font (size 1.27 1.27) (thickness 0.15)) (justify left bottom) hide)
    )
    (property "Datasheet" "https://product.tdk.com/en/search/capacitor/ceramic/mlcc/info?part_no=C1005X6S1A105K050BC" (at 292.1 24.13 0)
      (effects (font (size 1.27 1.27) (thickness 0.15)) (justify left bottom) hide)
    )
    (property "Manufacturer" "TDK" (at 297.18 24.13 0)
      (effects (font (size 1.27 1.27) (thickness 0.15)) (justify left bottom) hide)
    )
    (property "MPN" "C1005X6S1A105K050BC" (at 294.64 24.13 0)
      (effects (font (size 1.27 1.27) (thickness 0.15)) (justify left bottom) hide)
    )
    (property "Val" "1u" (at 279.4 43.1736 90)
      (effects (font (size 1.27 1.27) (thickness 0.15)) (justify right))
    )
    (property "License" "Apache-2.0" (at 299.72 24.13 0)
      (effects (font (size 1.27 1.27) (thickness 0.15)) (justify left bottom) hide)
    )
    (property "Author" "Antmicro" (at 302.26 24.13 0)
      (effects (font (size 1.27 1.27) (thickness 0.15)) (justify left bottom) hide)
    )
    (property "Voltage" "" (at 304.8 24.13 0)
      (effects (font (size 1.27 1.27)) (justify left bottom) hide)
    )
    (property "Dielectric" "" (at 307.34 24.13 0)
      (effects (font (size 1.27 1.27)) (justify left bottom) hide)
    )
    (pin "1")
    (pin "2")
    (instances
      (project "d1600e-psu-breakout-board"
        (path ""
          (reference "C22") (unit 1)
        )
      )
    )
  )

  (symbol (lib_id "antmicroCapacitors0402:C_100n_0402") (at 86.36 160.02 180) (unit 1)
    (in_bom yes) (on_board yes) (dnp no) (fields_autoplaced)
    (property "Reference" "C21" (at 83.8136 153.67 0)
      (effects (font (size 1.27 1.27)))
    )
    (property "Value" "C_100n_0402" (at 66.04 149.86 0)
      (effects (font (size 1.27 1.27) (thickness 0.15)) (justify left bottom) hide)
    )
    (property "Footprint" "antmicro-footprints:C_0402_1005Metric" (at 66.04 147.32 0)
      (effects (font (size 1.27 1.27) (thickness 0.15)) (justify left bottom) hide)
    )
    (property "Datasheet" "https://www.murata.com/products/productdetail?partno=GRM155R61H104KE14%23" (at 66.04 144.78 0)
      (effects (font (size 1.27 1.27) (thickness 0.15)) (justify left bottom) hide)
    )
    (property "Manufacturer" "Murata" (at 66.04 139.7 0)
      (effects (font (size 1.27 1.27) (thickness 0.15)) (justify left bottom) hide)
    )
    (property "MPN" "GRM155R61H104KE14D" (at 66.04 142.24 0)
      (effects (font (size 1.27 1.27) (thickness 0.15)) (justify left bottom) hide)
    )
    (property "Val" "100n" (at 83.8136 156.21 0)
      (effects (font (size 1.27 1.27) (thickness 0.15)))
    )
    (property "License" "Apache-2.0" (at 66.04 137.16 0)
      (effects (font (size 1.27 1.27) (thickness 0.15)) (justify left bottom) hide)
    )
    (property "Author" "Antmicro" (at 66.04 134.62 0)
      (effects (font (size 1.27 1.27) (thickness 0.15)) (justify left bottom) hide)
    )
    (property "Voltage" "50V" (at 66.04 132.08 0)
      (effects (font (size 1.27 1.27)) (justify left bottom) hide)
    )
    (property "Dielectric" "X5R" (at 66.04 129.54 0)
      (effects (font (size 1.27 1.27)) (justify left bottom) hide)
    )
    (pin "1")
    (pin "2")
    (instances
      (project "d1600e-psu-breakout-board"
        (path ""
          (reference "C21") (unit 1)
        )
      )
    )
  )

  (symbol (lib_id "antmicropower:GND") (at 93.98 161.29 0) (unit 1)
    (in_bom yes) (on_board yes) (dnp no)
    (property "Reference" "#PWR058" (at 93.98 167.64 0)
      (effects (font (size 1.27 1.27)) hide)
    )
    (property "Value" "GND" (at 102.87 166.37 0)
      (effects (font (size 1.27 1.27) (thickness 0.15)) (justify left bottom))
    )
    (property "Footprint" "" (at 102.87 168.91 0)
      (effects (font (size 1.27 1.27) (thickness 0.15)) (justify left bottom) hide)
    )
    (property "Datasheet" "" (at 102.87 173.99 0)
      (effects (font (size 1.27 1.27) (thickness 0.15)) (justify left bottom) hide)
    )
    (property "Author" "Antmicro" (at 102.87 168.91 0)
      (effects (font (size 1.27 1.27) (thickness 0.15)) (justify left bottom) hide)
    )
    (property "License" "Apache-2.0" (at 102.87 171.45 0)
      (effects (font (size 1.27 1.27) (thickness 0.15)) (justify left bottom) hide)
    )
    (pin "1")
    (instances
      (project "d1600e-psu-breakout-board"
        (path ""
          (reference "#PWR058") (unit 1)
        )
      )
    )
  )

  (symbol (lib_id "antmicropower:GND") (at 284.48 85.09 0) (unit 1)
    (in_bom yes) (on_board yes) (dnp no)
    (property "Reference" "#PWR0101" (at 284.48 91.44 0)
      (effects (font (size 1.27 1.27)) hide)
    )
    (property "Value" "GND" (at 284.48 88.9 0)
      (effects (font (size 1.27 1.27) (thickness 0.15)))
    )
    (property "Footprint" "" (at 293.37 92.71 0)
      (effects (font (size 1.27 1.27) (thickness 0.15)) (justify left bottom) hide)
    )
    (property "Datasheet" "" (at 293.37 97.79 0)
      (effects (font (size 1.27 1.27) (thickness 0.15)) (justify left bottom) hide)
    )
    (property "Author" "Antmicro" (at 293.37 92.71 0)
      (effects (font (size 1.27 1.27) (thickness 0.15)) (justify left bottom) hide)
    )
    (property "License" "Apache-2.0" (at 293.37 95.25 0)
      (effects (font (size 1.27 1.27) (thickness 0.15)) (justify left bottom) hide)
    )
    (pin "1")
    (instances
      (project "d1600e-psu-breakout-board"
        (path ""
          (reference "#PWR0101") (unit 1)
        )
      )
    )
  )

  (symbol (lib_name "R_0R_0402_3") (lib_id "antmicroResistors0402:R_0R_0402") (at 336.55 64.77 270) (unit 1)
    (in_bom no) (on_board yes) (dnp yes)
    (property "Reference" "R30" (at 337.82 64.77 90)
      (effects (font (size 1.27 1.27)) (justify left))
    )
    (property "Value" "R_0R_0402" (at 323.85 85.09 0)
      (effects (font (size 1.27 1.27) (thickness 0.15)) (justify left bottom) hide)
    )
    (property "Footprint" "antmicro-footprints:R_0402_1005Metric" (at 321.31 85.09 0)
      (effects (font (size 1.27 1.27) (thickness 0.15)) (justify left bottom) hide)
    )
    (property "Datasheet" "https://industrial.panasonic.com/cdbs/www-data/pdf/RDA0000/AOA0000C301.pdf" (at 318.77 85.09 0)
      (effects (font (size 1.27 1.27) (thickness 0.15)) (justify left bottom) hide)
    )
    (property "Manufacturer" "Panasonic" (at 313.69 85.09 0)
      (effects (font (size 1.27 1.27) (thickness 0.15)) (justify left bottom) hide)
    )
    (property "MPN" "ERJ2GE0R00X" (at 316.23 85.09 0)
      (effects (font (size 1.27 1.27) (thickness 0.15)) (justify left bottom) hide)
    )
    (property "Val" "0R" (at 337.82 67.31 90)
      (effects (font (size 1.27 1.27) (thickness 0.15)) (justify left))
    )
    (property "DNP" "DNP" (at 337.82 69.85 90)
      (effects (font (size 1.27 1.27)) (justify left))
    )
    (property "License" "Apache-2.0" (at 311.15 85.09 0)
      (effects (font (size 1.27 1.27) (thickness 0.15)) (justify left bottom) hide)
    )
    (property "Author" "Antmicro" (at 308.61 85.09 0)
      (effects (font (size 1.27 1.27) (thickness 0.15)) (justify left bottom) hide)
    )
    (property "Tolerance" "~" (at 326.39 85.09 0)
      (effects (font (size 1.27 1.27)) (justify left bottom) hide)
    )
    (property "Current" "1A" (at 306.07 85.09 0)
      (effects (font (size 1.27 1.27) (thickness 0.15)) (justify left bottom) hide)
    )
    (pin "1")
    (pin "2")
    (instances
      (project "d1600e-psu-breakout-board"
        (path ""
          (reference "R30") (unit 1)
        )
      )
    )
  )

  (symbol (lib_name "R_0R_0402_4") (lib_id "antmicroResistors0402:R_0R_0402") (at 345.44 64.77 270) (unit 1)
    (in_bom no) (on_board yes) (dnp yes)
    (property "Reference" "R32" (at 346.71 64.77 90)
      (effects (font (size 1.27 1.27)) (justify left))
    )
    (property "Value" "R_0R_0402" (at 332.74 85.09 0)
      (effects (font (size 1.27 1.27) (thickness 0.15)) (justify left bottom) hide)
    )
    (property "Footprint" "antmicro-footprints:R_0402_1005Metric" (at 330.2 85.09 0)
      (effects (font (size 1.27 1.27) (thickness 0.15)) (justify left bottom) hide)
    )
    (property "Datasheet" "https://industrial.panasonic.com/cdbs/www-data/pdf/RDA0000/AOA0000C301.pdf" (at 327.66 85.09 0)
      (effects (font (size 1.27 1.27) (thickness 0.15)) (justify left bottom) hide)
    )
    (property "Manufacturer" "Panasonic" (at 322.58 85.09 0)
      (effects (font (size 1.27 1.27) (thickness 0.15)) (justify left bottom) hide)
    )
    (property "MPN" "ERJ2GE0R00X" (at 325.12 85.09 0)
      (effects (font (size 1.27 1.27) (thickness 0.15)) (justify left bottom) hide)
    )
    (property "Val" "0R" (at 346.71 67.31 90)
      (effects (font (size 1.27 1.27) (thickness 0.15)) (justify left))
    )
    (property "DNP" "DNP" (at 346.71 69.85 90)
      (effects (font (size 1.27 1.27)) (justify left))
    )
    (property "License" "Apache-2.0" (at 320.04 85.09 0)
      (effects (font (size 1.27 1.27) (thickness 0.15)) (justify left bottom) hide)
    )
    (property "Author" "Antmicro" (at 317.5 85.09 0)
      (effects (font (size 1.27 1.27) (thickness 0.15)) (justify left bottom) hide)
    )
    (property "Tolerance" "~" (at 335.28 85.09 0)
      (effects (font (size 1.27 1.27)) (justify left bottom) hide)
    )
    (property "Current" "1A" (at 314.96 85.09 0)
      (effects (font (size 1.27 1.27) (thickness 0.15)) (justify left bottom) hide)
    )
    (pin "1")
    (pin "2")
    (instances
      (project "d1600e-psu-breakout-board"
        (path ""
          (reference "R32") (unit 1)
        )
      )
    )
  )

  (symbol (lib_id "antmicropower:GND") (at 276.86 46.99 0) (unit 1)
    (in_bom yes) (on_board yes) (dnp no)
    (property "Reference" "#PWR048" (at 276.86 53.34 0)
      (effects (font (size 1.27 1.27)) hide)
    )
    (property "Value" "GND" (at 276.86 50.8 0)
      (effects (font (size 1.27 1.27) (thickness 0.15)))
    )
    (property "Footprint" "" (at 285.75 54.61 0)
      (effects (font (size 1.27 1.27) (thickness 0.15)) (justify left bottom) hide)
    )
    (property "Datasheet" "" (at 285.75 59.69 0)
      (effects (font (size 1.27 1.27) (thickness 0.15)) (justify left bottom) hide)
    )
    (property "Author" "Antmicro" (at 285.75 54.61 0)
      (effects (font (size 1.27 1.27) (thickness 0.15)) (justify left bottom) hide)
    )
    (property "License" "Apache-2.0" (at 285.75 57.15 0)
      (effects (font (size 1.27 1.27) (thickness 0.15)) (justify left bottom) hide)
    )
    (pin "1")
    (instances
      (project "d1600e-psu-breakout-board"
        (path ""
          (reference "#PWR048") (unit 1)
        )
      )
    )
  )

  (symbol (lib_id "antmicropower:GND") (at 312.42 85.09 0) (unit 1)
    (in_bom yes) (on_board yes) (dnp no)
    (property "Reference" "#PWR0109" (at 312.42 91.44 0)
      (effects (font (size 1.27 1.27)) hide)
    )
    (property "Value" "GND" (at 312.42 88.9 0)
      (effects (font (size 1.27 1.27) (thickness 0.15)))
    )
    (property "Footprint" "" (at 321.31 92.71 0)
      (effects (font (size 1.27 1.27) (thickness 0.15)) (justify left bottom) hide)
    )
    (property "Datasheet" "" (at 321.31 97.79 0)
      (effects (font (size 1.27 1.27) (thickness 0.15)) (justify left bottom) hide)
    )
    (property "Author" "Antmicro" (at 321.31 92.71 0)
      (effects (font (size 1.27 1.27) (thickness 0.15)) (justify left bottom) hide)
    )
    (property "License" "Apache-2.0" (at 321.31 95.25 0)
      (effects (font (size 1.27 1.27) (thickness 0.15)) (justify left bottom) hide)
    )
    (pin "1")
    (instances
      (project "d1600e-psu-breakout-board"
        (path ""
          (reference "#PWR0109") (unit 1)
        )
      )
    )
  )

  (symbol (lib_id "antmicroFerriteBeadsandChips:FB_600Z_0.5A_Murata-BLM18AG_0603") (at 323.85 64.77 180) (unit 1)
    (in_bom yes) (on_board yes) (dnp no)
    (property "Reference" "FB4" (at 321.31 59.69 0)
      (effects (font (size 1.27 1.27)))
    )
    (property "Value" "FB_600Z_0.5A_Murata-BLM18AG_0603" (at 308.61 62.23 0)
      (effects (font (size 1.27 1.27) (thickness 0.15)) (justify left bottom) hide)
    )
    (property "Footprint" "antmicro-footprints:FB_0603_1608Metric" (at 308.61 57.15 0)
      (effects (font (size 1.27 1.27) (thickness 0.15)) (justify left bottom) hide)
    )
    (property "Datasheet" "https://www.murata.com/en-us/products/productdata/8796738650142/ENFA0003.pdf" (at 308.61 54.61 0)
      (effects (font (size 1.27 1.27) (thickness 0.15)) (justify left bottom) hide)
    )
    (property "MPN" "BLM18AG601SN1D" (at 308.61 52.07 0)
      (effects (font (size 1.27 1.27) (thickness 0.15)) (justify left bottom) hide)
    )
    (property "Manufacturer" "Murata" (at 308.61 49.53 0)
      (effects (font (size 1.27 1.27) (thickness 0.15)) (justify left bottom) hide)
    )
    (property "Val" "600Z/0.5A" (at 326.39 60.96 0)
      (effects (font (size 1.27 1.27)) (justify left bottom))
    )
    (property "Current" "" (at 303.53 41.91 0)
      (effects (font (size 1.27 1.27) (thickness 0.15)) (justify left bottom) hide)
    )
    (property "Author" "Antmicro" (at 308.61 46.99 0)
      (effects (font (size 1.27 1.27) (thickness 0.15)) (justify left bottom) hide)
    )
    (property "License" "Apache-2.0" (at 308.61 44.45 0)
      (effects (font (size 1.27 1.27) (thickness 0.15)) (justify left bottom) hide)
    )
    (pin "1")
    (pin "2")
    (instances
      (project "d1600e-psu-breakout-board"
        (path ""
          (reference "FB4") (unit 1)
        )
      )
    )
  )

  (symbol (lib_name "R_0R_0402_5") (lib_id "antmicroResistors0402:R_0R_0402") (at 142.24 104.14 0) (unit 1)
    (in_bom yes) (on_board yes) (dnp no)
    (property "Reference" "R70" (at 144.78 99.06 0)
      (effects (font (size 1.27 1.27)))
    )
    (property "Value" "R_0R_0402" (at 162.56 116.84 0)
      (effects (font (size 1.27 1.27) (thickness 0.15)) (justify left bottom) hide)
    )
    (property "Footprint" "antmicro-footprints:R_0402_1005Metric" (at 162.56 119.38 0)
      (effects (font (size 1.27 1.27) (thickness 0.15)) (justify left bottom) hide)
    )
    (property "Datasheet" "https://industrial.panasonic.com/cdbs/www-data/pdf/RDA0000/AOA0000C301.pdf" (at 162.56 121.92 0)
      (effects (font (size 1.27 1.27) (thickness 0.15)) (justify left bottom) hide)
    )
    (property "Manufacturer" "Panasonic" (at 162.56 127 0)
      (effects (font (size 1.27 1.27) (thickness 0.15)) (justify left bottom) hide)
    )
    (property "MPN" "ERJ2GE0R00X" (at 162.56 124.46 0)
      (effects (font (size 1.27 1.27) (thickness 0.15)) (justify left bottom) hide)
    )
    (property "Val" "0R" (at 144.78 101.6 0)
      (effects (font (size 1.27 1.27) (thickness 0.15)))
    )
    (property "License" "Apache-2.0" (at 162.56 129.54 0)
      (effects (font (size 1.27 1.27) (thickness 0.15)) (justify left bottom) hide)
    )
    (property "Author" "Antmicro" (at 162.56 132.08 0)
      (effects (font (size 1.27 1.27) (thickness 0.15)) (justify left bottom) hide)
    )
    (property "Tolerance" "~" (at 162.56 114.3 0)
      (effects (font (size 1.27 1.27)) (justify left bottom) hide)
    )
    (property "Current" "1A" (at 162.56 134.62 0)
      (effects (font (size 1.27 1.27) (thickness 0.15)) (justify left bottom) hide)
    )
    (pin "1")
    (pin "2")
    (instances
      (project "d1600e-psu-breakout-board"
        (path ""
          (reference "R70") (unit 1)
        )
      )
    )
  )

  (symbol (lib_name "C_100n_0402_1") (lib_id "antmicroCapacitors0402:C_100n_0402") (at 238.76 38.1 0) (mirror x) (unit 1)
    (in_bom yes) (on_board yes) (dnp no)
    (property "Reference" "C29" (at 245.11 36.83 0)
      (effects (font (size 1.27 1.27)))
    )
    (property "Value" "C_100n_0402" (at 259.08 27.94 0)
      (effects (font (size 1.27 1.27) (thickness 0.15)) (justify left bottom) hide)
    )
    (property "Footprint" "antmicro-footprints:C_0402_1005Metric" (at 259.08 25.4 0)
      (effects (font (size 1.27 1.27) (thickness 0.15)) (justify left bottom) hide)
    )
    (property "Datasheet" "https://www.murata.com/products/productdetail?partno=GRM155R61H104KE14%23" (at 259.08 22.86 0)
      (effects (font (size 1.27 1.27) (thickness 0.15)) (justify left bottom) hide)
    )
    (property "Manufacturer" "Murata" (at 259.08 17.78 0)
      (effects (font (size 1.27 1.27) (thickness 0.15)) (justify left bottom) hide)
    )
    (property "MPN" "GRM155R61H104KE14D" (at 259.08 20.32 0)
      (effects (font (size 1.27 1.27) (thickness 0.15)) (justify left bottom) hide)
    )
    (property "Val" "100n" (at 237.49 36.83 0)
      (effects (font (size 1.27 1.27) (thickness 0.15)))
    )
    (property "License" "Apache-2.0" (at 259.08 15.24 0)
      (effects (font (size 1.27 1.27) (thickness 0.15)) (justify left bottom) hide)
    )
    (property "Author" "Antmicro" (at 259.08 12.7 0)
      (effects (font (size 1.27 1.27) (thickness 0.15)) (justify left bottom) hide)
    )
    (property "Voltage" "50V" (at 259.08 10.16 0)
      (effects (font (size 1.27 1.27)) (justify left bottom) hide)
    )
    (property "Dielectric" "X5R" (at 259.08 7.62 0)
      (effects (font (size 1.27 1.27)) (justify left bottom) hide)
    )
    (pin "1")
    (pin "2")
    (instances
      (project "d1600e-psu-breakout-board"
        (path ""
          (reference "C29") (unit 1)
        )
      )
    )
  )

  (symbol (lib_id "antmicroResistors0402:R_100k_0.1%_0402") (at 134.62 99.06 90) (unit 1)
    (in_bom yes) (on_board yes) (dnp no)
    (property "Reference" "R2" (at 135.89 93.98 90)
      (effects (font (size 1.27 1.27)) (justify right))
    )
    (property "Value" "R_100k_0.1%_0402" (at 147.32 78.74 0)
      (effects (font (size 1.27 1.27) (thickness 0.15)) (justify left bottom) hide)
    )
    (property "Footprint" "antmicro-footprints:R_0402_1005Metric" (at 149.86 78.74 0)
      (effects (font (size 1.27 1.27) (thickness 0.15)) (justify left bottom) hide)
    )
    (property "Datasheet" "https://www.mouser.pl/datasheet/2/447/PYu_RC_Group_51_RoHS_L_11-1984063.pdf" (at 152.4 78.74 0)
      (effects (font (size 1.27 1.27) (thickness 0.15)) (justify left bottom) hide)
    )
    (property "Manufacturer" "Yageo" (at 157.48 78.74 0)
      (effects (font (size 1.27 1.27) (thickness 0.15)) (justify left bottom) hide)
    )
    (property "MPN" "RC0402BR-07100KL" (at 154.94 78.74 0)
      (effects (font (size 1.27 1.27) (thickness 0.15)) (justify left bottom) hide)
    )
    (property "Val" "100k" (at 135.89 96.52 90)
      (effects (font (size 1.27 1.27) (thickness 0.15)) (justify right))
    )
    (property "License" "Apache-2.0" (at 160.02 78.74 0)
      (effects (font (size 1.27 1.27) (thickness 0.15)) (justify left bottom) hide)
    )
    (property "Author" "Antmicro" (at 162.56 78.74 0)
      (effects (font (size 1.27 1.27) (thickness 0.15)) (justify left bottom) hide)
    )
    (property "Tolerance" "0.1%" (at 135.89 99.06 90)
      (effects (font (size 1.27 1.27)) (justify right))
    )
    (pin "1")
    (pin "2")
    (instances
      (project "d1600e-psu-breakout-board"
        (path ""
          (reference "R2") (unit 1)
        )
      )
    )
  )

  (symbol (lib_id "antmicropower:GND") (at 134.62 116.84 0) (unit 1)
    (in_bom yes) (on_board yes) (dnp no)
    (property "Reference" "#PWR011" (at 134.62 123.19 0)
      (effects (font (size 1.27 1.27)) hide)
    )
    (property "Value" "GND" (at 134.62 120.65 0)
      (effects (font (size 1.27 1.27) (thickness 0.15)))
    )
    (property "Footprint" "" (at 143.51 124.46 0)
      (effects (font (size 1.27 1.27) (thickness 0.15)) (justify left bottom) hide)
    )
    (property "Datasheet" "" (at 143.51 129.54 0)
      (effects (font (size 1.27 1.27) (thickness 0.15)) (justify left bottom) hide)
    )
    (property "Author" "Antmicro" (at 143.51 124.46 0)
      (effects (font (size 1.27 1.27) (thickness 0.15)) (justify left bottom) hide)
    )
    (property "License" "Apache-2.0" (at 143.51 127 0)
      (effects (font (size 1.27 1.27) (thickness 0.15)) (justify left bottom) hide)
    )
    (pin "1")
    (instances
      (project "d1600e-psu-breakout-board"
        (path ""
          (reference "#PWR011") (unit 1)
        )
      )
    )
  )

  (symbol (lib_name "C_100n_0402_1") (lib_id "antmicroCapacitors0402:C_100n_0402") (at 189.23 36.83 0) (mirror x) (unit 1)
    (in_bom yes) (on_board yes) (dnp no)
    (property "Reference" "C31" (at 195.58 35.56 0)
      (effects (font (size 1.27 1.27)))
    )
    (property "Value" "C_100n_0402" (at 209.55 26.67 0)
      (effects (font (size 1.27 1.27) (thickness 0.15)) (justify left bottom) hide)
    )
    (property "Footprint" "antmicro-footprints:C_0402_1005Metric" (at 209.55 24.13 0)
      (effects (font (size 1.27 1.27) (thickness 0.15)) (justify left bottom) hide)
    )
    (property "Datasheet" "https://www.murata.com/products/productdetail?partno=GRM155R61H104KE14%23" (at 209.55 21.59 0)
      (effects (font (size 1.27 1.27) (thickness 0.15)) (justify left bottom) hide)
    )
    (property "Manufacturer" "Murata" (at 209.55 16.51 0)
      (effects (font (size 1.27 1.27) (thickness 0.15)) (justify left bottom) hide)
    )
    (property "MPN" "GRM155R61H104KE14D" (at 209.55 19.05 0)
      (effects (font (size 1.27 1.27) (thickness 0.15)) (justify left bottom) hide)
    )
    (property "Val" "100n" (at 187.96 35.56 0)
      (effects (font (size 1.27 1.27) (thickness 0.15)))
    )
    (property "License" "Apache-2.0" (at 209.55 13.97 0)
      (effects (font (size 1.27 1.27) (thickness 0.15)) (justify left bottom) hide)
    )
    (property "Author" "Antmicro" (at 209.55 11.43 0)
      (effects (font (size 1.27 1.27) (thickness 0.15)) (justify left bottom) hide)
    )
    (property "Voltage" "50V" (at 209.55 8.89 0)
      (effects (font (size 1.27 1.27)) (justify left bottom) hide)
    )
    (property "Dielectric" "X5R" (at 209.55 6.35 0)
      (effects (font (size 1.27 1.27)) (justify left bottom) hide)
    )
    (pin "1")
    (pin "2")
    (instances
      (project "d1600e-psu-breakout-board"
        (path ""
          (reference "C31") (unit 1)
        )
      )
    )
  )

  (symbol (lib_id "antmicroResistors0402:R_15k4_0.1%_0402") (at 134.62 107.95 270) (unit 1)
    (in_bom yes) (on_board yes) (dnp no)
    (property "Reference" "R59" (at 135.89 107.95 90)
      (effects (font (size 1.27 1.27)) (justify left))
    )
    (property "Value" "R_15k4_0.1%_0402" (at 121.92 128.27 0)
      (effects (font (size 1.27 1.27) (thickness 0.15)) (justify left bottom) hide)
    )
    (property "Footprint" "antmicro-footprints:R_0402_1005Metric" (at 119.38 128.27 0)
      (effects (font (size 1.27 1.27) (thickness 0.15)) (justify left bottom) hide)
    )
    (property "Datasheet" "https://www.mouser.pl/datasheet/2/315/AOA0000C307-1149632.pdf" (at 116.84 128.27 0)
      (effects (font (size 1.27 1.27) (thickness 0.15)) (justify left bottom) hide)
    )
    (property "Manufacturer" "Panasonic" (at 111.76 128.27 0)
      (effects (font (size 1.27 1.27) (thickness 0.15)) (justify left bottom) hide)
    )
    (property "MPN" "ERA-2AEB1542X" (at 114.3 128.27 0)
      (effects (font (size 1.27 1.27) (thickness 0.15)) (justify left bottom) hide)
    )
    (property "Val" "15k4" (at 135.89 110.49 90)
      (effects (font (size 1.27 1.27) (thickness 0.15)) (justify left))
    )
    (property "License" "Apache-2.0" (at 109.22 128.27 0)
      (effects (font (size 1.27 1.27) (thickness 0.15)) (justify left bottom) hide)
    )
    (property "Author" "Antmicro" (at 106.68 128.27 0)
      (effects (font (size 1.27 1.27) (thickness 0.15)) (justify left bottom) hide)
    )
    (property "Tolerance" "0.1%" (at 135.89 113.03 90)
      (effects (font (size 1.27 1.27)) (justify left))
    )
    (pin "1")
    (pin "2")
    (instances
      (project "d1600e-psu-breakout-board"
        (path ""
          (reference "R59") (unit 1)
        )
      )
    )
  )

  (symbol (lib_id "antmicropower:GND") (at 153.67 55.88 0) (unit 1)
    (in_bom yes) (on_board yes) (dnp no)
    (property "Reference" "#PWR026" (at 153.67 62.23 0)
      (effects (font (size 1.27 1.27)) hide)
    )
    (property "Value" "GND" (at 153.67 59.69 0)
      (effects (font (size 1.27 1.27) (thickness 0.15)))
    )
    (property "Footprint" "" (at 162.56 63.5 0)
      (effects (font (size 1.27 1.27) (thickness 0.15)) (justify left bottom) hide)
    )
    (property "Datasheet" "" (at 162.56 68.58 0)
      (effects (font (size 1.27 1.27) (thickness 0.15)) (justify left bottom) hide)
    )
    (property "Author" "Antmicro" (at 162.56 63.5 0)
      (effects (font (size 1.27 1.27) (thickness 0.15)) (justify left bottom) hide)
    )
    (property "License" "Apache-2.0" (at 162.56 66.04 0)
      (effects (font (size 1.27 1.27) (thickness 0.15)) (justify left bottom) hide)
    )
    (pin "1")
    (instances
      (project "d1600e-psu-breakout-board"
        (path ""
          (reference "#PWR026") (unit 1)
        )
      )
    )
  )

  (symbol (lib_id "antmicropower:GND") (at 252.73 57.15 0) (unit 1)
    (in_bom yes) (on_board yes) (dnp no)
    (property "Reference" "#PWR047" (at 252.73 63.5 0)
      (effects (font (size 1.27 1.27)) hide)
    )
    (property "Value" "GND" (at 252.73 60.96 0)
      (effects (font (size 1.27 1.27) (thickness 0.15)))
    )
    (property "Footprint" "" (at 261.62 64.77 0)
      (effects (font (size 1.27 1.27) (thickness 0.15)) (justify left bottom) hide)
    )
    (property "Datasheet" "" (at 261.62 69.85 0)
      (effects (font (size 1.27 1.27) (thickness 0.15)) (justify left bottom) hide)
    )
    (property "Author" "Antmicro" (at 261.62 64.77 0)
      (effects (font (size 1.27 1.27) (thickness 0.15)) (justify left bottom) hide)
    )
    (property "License" "Apache-2.0" (at 261.62 67.31 0)
      (effects (font (size 1.27 1.27) (thickness 0.15)) (justify left bottom) hide)
    )
    (pin "1")
    (instances
      (project "d1600e-psu-breakout-board"
        (path ""
          (reference "#PWR047") (unit 1)
        )
      )
    )
  )

  (symbol (lib_name "TMCS1100A2-Q1_1") (lib_id "antmicroPowerMeasurement:TMCS1100A2-Q1") (at 83.82 48.26 0) (unit 1)
    (in_bom yes) (on_board yes) (dnp no)
    (property "Reference" "U9" (at 92.71 41.91 0)
      (effects (font (size 1.27 1.27)))
    )
    (property "Value" "TMCS1100A2-Q1" (at 116.84 55.88 0)
      (effects (font (size 1.27 1.27) (thickness 0.15)) (justify left bottom) hide)
    )
    (property "Footprint" "antmicro-footprints:SOIC-8_3.9x4.9x1.75mm_P1.27mm" (at 116.84 58.42 0)
      (effects (font (size 1.27 1.27) (thickness 0.15)) (justify left bottom) hide)
    )
    (property "Datasheet" "https://www.ti.com/lit/ds/symlink/tmcs1100-q1.pdf?ts=1647195769204&ref_url=https%253A%252F%252Fwww.mouser.de%252F" (at 116.84 60.96 0)
      (effects (font (size 1.27 1.27) (thickness 0.15)) (justify left bottom) hide)
    )
    (property "MPN" "TMCS1100A2QDRQ1" (at 92.71 44.45 0)
      (effects (font (size 1.27 1.27) (thickness 0.15)))
    )
    (property "Manufacturer" "Texas Instruments" (at 116.84 63.5 0)
      (effects (font (size 1.27 1.27) (thickness 0.15)) (justify left bottom) hide)
    )
    (property "Author" "Antmicro" (at 116.84 66.04 0)
      (effects (font (size 1.27 1.27) (thickness 0.15)) (justify left bottom) hide)
    )
    (property "License" "Apache-2.0" (at 116.84 68.58 0)
      (effects (font (size 1.27 1.27) (thickness 0.15)) (justify left bottom) hide)
    )
    (pin "1")
    (pin "2")
    (pin "3")
    (pin "4")
    (pin "5")
    (pin "6")
    (pin "7")
    (pin "8")
    (instances
      (project "d1600e-psu-breakout-board"
        (path ""
          (reference "U9") (unit 1)
        )
      )
    )
  )

  (symbol (lib_id "antmicropower:GND") (at 152.4 116.84 0) (unit 1)
    (in_bom yes) (on_board yes) (dnp no)
    (property "Reference" "#PWR016" (at 152.4 123.19 0)
      (effects (font (size 1.27 1.27)) hide)
    )
    (property "Value" "GND" (at 152.4 120.65 0)
      (effects (font (size 1.27 1.27) (thickness 0.15)))
    )
    (property "Footprint" "" (at 161.29 124.46 0)
      (effects (font (size 1.27 1.27) (thickness 0.15)) (justify left bottom) hide)
    )
    (property "Datasheet" "" (at 161.29 129.54 0)
      (effects (font (size 1.27 1.27) (thickness 0.15)) (justify left bottom) hide)
    )
    (property "Author" "Antmicro" (at 161.29 124.46 0)
      (effects (font (size 1.27 1.27) (thickness 0.15)) (justify left bottom) hide)
    )
    (property "License" "Apache-2.0" (at 161.29 127 0)
      (effects (font (size 1.27 1.27) (thickness 0.15)) (justify left bottom) hide)
    )
    (pin "1")
    (instances
      (project "d1600e-psu-breakout-board"
        (path ""
          (reference "#PWR016") (unit 1)
        )
      )
    )
  )

  (symbol (lib_name "C_100n_0402_1") (lib_id "antmicroCapacitors0402:C_100n_0402") (at 139.7 36.83 0) (mirror x) (unit 1)
    (in_bom yes) (on_board yes) (dnp no)
    (property "Reference" "C32" (at 146.05 35.56 0)
      (effects (font (size 1.27 1.27)))
    )
    (property "Value" "C_100n_0402" (at 160.02 26.67 0)
      (effects (font (size 1.27 1.27) (thickness 0.15)) (justify left bottom) hide)
    )
    (property "Footprint" "antmicro-footprints:C_0402_1005Metric" (at 160.02 24.13 0)
      (effects (font (size 1.27 1.27) (thickness 0.15)) (justify left bottom) hide)
    )
    (property "Datasheet" "https://www.murata.com/products/productdetail?partno=GRM155R61H104KE14%23" (at 160.02 21.59 0)
      (effects (font (size 1.27 1.27) (thickness 0.15)) (justify left bottom) hide)
    )
    (property "Manufacturer" "Murata" (at 160.02 16.51 0)
      (effects (font (size 1.27 1.27) (thickness 0.15)) (justify left bottom) hide)
    )
    (property "MPN" "GRM155R61H104KE14D" (at 160.02 19.05 0)
      (effects (font (size 1.27 1.27) (thickness 0.15)) (justify left bottom) hide)
    )
    (property "Val" "100n" (at 138.43 35.56 0)
      (effects (font (size 1.27 1.27) (thickness 0.15)))
    )
    (property "License" "Apache-2.0" (at 160.02 13.97 0)
      (effects (font (size 1.27 1.27) (thickness 0.15)) (justify left bottom) hide)
    )
    (property "Author" "Antmicro" (at 160.02 11.43 0)
      (effects (font (size 1.27 1.27) (thickness 0.15)) (justify left bottom) hide)
    )
    (property "Voltage" "50V" (at 160.02 8.89 0)
      (effects (font (size 1.27 1.27)) (justify left bottom) hide)
    )
    (property "Dielectric" "X5R" (at 160.02 6.35 0)
      (effects (font (size 1.27 1.27)) (justify left bottom) hide)
    )
    (pin "1")
    (pin "2")
    (instances
      (project "d1600e-psu-breakout-board"
        (path ""
          (reference "C32") (unit 1)
        )
      )
    )
  )

  (symbol (lib_name "TMCS1100A2-Q1_1") (lib_id "antmicroPowerMeasurement:TMCS1100A2-Q1") (at 182.88 48.26 0) (unit 1)
    (in_bom yes) (on_board yes) (dnp no)
    (property "Reference" "U12" (at 191.77 41.91 0)
      (effects (font (size 1.27 1.27)))
    )
    (property "Value" "TMCS1100A2-Q1" (at 215.9 55.88 0)
      (effects (font (size 1.27 1.27) (thickness 0.15)) (justify left bottom) hide)
    )
    (property "Footprint" "antmicro-footprints:SOIC-8_3.9x4.9x1.75mm_P1.27mm" (at 215.9 58.42 0)
      (effects (font (size 1.27 1.27) (thickness 0.15)) (justify left bottom) hide)
    )
    (property "Datasheet" "https://www.ti.com/lit/ds/symlink/tmcs1100-q1.pdf?ts=1647195769204&ref_url=https%253A%252F%252Fwww.mouser.de%252F" (at 215.9 60.96 0)
      (effects (font (size 1.27 1.27) (thickness 0.15)) (justify left bottom) hide)
    )
    (property "MPN" "TMCS1100A2QDRQ1" (at 191.77 44.45 0)
      (effects (font (size 1.27 1.27) (thickness 0.15)))
    )
    (property "Manufacturer" "Texas Instruments" (at 215.9 63.5 0)
      (effects (font (size 1.27 1.27) (thickness 0.15)) (justify left bottom) hide)
    )
    (property "Author" "Antmicro" (at 215.9 66.04 0)
      (effects (font (size 1.27 1.27) (thickness 0.15)) (justify left bottom) hide)
    )
    (property "License" "Apache-2.0" (at 215.9 68.58 0)
      (effects (font (size 1.27 1.27) (thickness 0.15)) (justify left bottom) hide)
    )
    (pin "1")
    (pin "2")
    (pin "3")
    (pin "4")
    (pin "5")
    (pin "6")
    (pin "7")
    (pin "8")
    (instances
      (project "d1600e-psu-breakout-board"
        (path ""
          (reference "U12") (unit 1)
        )
      )
    )
  )

  (symbol (lib_name "TMCS1100A2-Q1_1") (lib_id "antmicroPowerMeasurement:TMCS1100A2-Q1") (at 133.35 48.26 0) (unit 1)
    (in_bom yes) (on_board yes) (dnp no)
    (property "Reference" "U11" (at 142.24 41.91 0)
      (effects (font (size 1.27 1.27)))
    )
    (property "Value" "TMCS1100A2-Q1" (at 166.37 55.88 0)
      (effects (font (size 1.27 1.27) (thickness 0.15)) (justify left bottom) hide)
    )
    (property "Footprint" "antmicro-footprints:SOIC-8_3.9x4.9x1.75mm_P1.27mm" (at 166.37 58.42 0)
      (effects (font (size 1.27 1.27) (thickness 0.15)) (justify left bottom) hide)
    )
    (property "Datasheet" "https://www.ti.com/lit/ds/symlink/tmcs1100-q1.pdf?ts=1647195769204&ref_url=https%253A%252F%252Fwww.mouser.de%252F" (at 166.37 60.96 0)
      (effects (font (size 1.27 1.27) (thickness 0.15)) (justify left bottom) hide)
    )
    (property "MPN" "TMCS1100A2QDRQ1" (at 142.24 44.45 0)
      (effects (font (size 1.27 1.27) (thickness 0.15)))
    )
    (property "Manufacturer" "Texas Instruments" (at 166.37 63.5 0)
      (effects (font (size 1.27 1.27) (thickness 0.15)) (justify left bottom) hide)
    )
    (property "Author" "Antmicro" (at 166.37 66.04 0)
      (effects (font (size 1.27 1.27) (thickness 0.15)) (justify left bottom) hide)
    )
    (property "License" "Apache-2.0" (at 166.37 68.58 0)
      (effects (font (size 1.27 1.27) (thickness 0.15)) (justify left bottom) hide)
    )
    (pin "1")
    (pin "2")
    (pin "3")
    (pin "4")
    (pin "5")
    (pin "6")
    (pin "7")
    (pin "8")
    (instances
      (project "d1600e-psu-breakout-board"
        (path ""
          (reference "U11") (unit 1)
        )
      )
    )
  )

  (symbol (lib_id "antmicropower:GND") (at 203.2 55.88 0) (unit 1)
    (in_bom yes) (on_board yes) (dnp no)
    (property "Reference" "#PWR045" (at 203.2 62.23 0)
      (effects (font (size 1.27 1.27)) hide)
    )
    (property "Value" "GND" (at 203.2 59.69 0)
      (effects (font (size 1.27 1.27) (thickness 0.15)))
    )
    (property "Footprint" "" (at 212.09 63.5 0)
      (effects (font (size 1.27 1.27) (thickness 0.15)) (justify left bottom) hide)
    )
    (property "Datasheet" "" (at 212.09 68.58 0)
      (effects (font (size 1.27 1.27) (thickness 0.15)) (justify left bottom) hide)
    )
    (property "Author" "Antmicro" (at 212.09 63.5 0)
      (effects (font (size 1.27 1.27) (thickness 0.15)) (justify left bottom) hide)
    )
    (property "License" "Apache-2.0" (at 212.09 66.04 0)
      (effects (font (size 1.27 1.27) (thickness 0.15)) (justify left bottom) hide)
    )
    (pin "1")
    (instances
      (project "d1600e-psu-breakout-board"
        (path ""
          (reference "#PWR045") (unit 1)
        )
      )
    )
  )

  (symbol (lib_id "antmicroTVSDiodes:PESD5V0S2BQA") (at 154.94 109.22 0) (unit 1)
    (in_bom yes) (on_board yes) (dnp no) (fields_autoplaced)
    (property "Reference" "D20" (at 168.91 110.49 0)
      (effects (font (size 1.27 1.27)) (justify left))
    )
    (property "Value" "PESD5V0S2BQA" (at 182.88 119.38 0)
      (effects (font (size 1.27 1.27) (thickness 0.15)) (justify left bottom) hide)
    )
    (property "Footprint" "antmicro-footprints:TPD2E009DRTR" (at 182.88 121.92 0)
      (effects (font (size 1.27 1.27) (thickness 0.15)) (justify left bottom) hide)
    )
    (property "Datasheet" "https://4donline.ihs.com/images/VipMasterIC/IC/NEXP/NEXP-S-A0003105620/NEXP-S-A0003107857-1.pdf?hkey=6D3A4C79FDBF58556ACFDE234799DDF0" (at 182.88 124.46 0)
      (effects (font (size 1.27 1.27) (thickness 0.15)) (justify left bottom) hide)
    )
    (property "MPN" "PESD5V0S2BQA" (at 168.91 113.03 0)
      (effects (font (size 1.27 1.27) (thickness 0.15)) (justify left))
    )
    (property "Manufacturer" "Nexperia" (at 182.88 116.84 0)
      (effects (font (size 1.27 1.27) (thickness 0.15)) (justify left bottom) hide)
    )
    (property "Author" "Antmicro" (at 182.88 127 0)
      (effects (font (size 1.27 1.27) (thickness 0.15)) (justify left bottom) hide)
    )
    (property "License" "Apache-2.0" (at 182.88 129.54 0)
      (effects (font (size 1.27 1.27) (thickness 0.15)) (justify left bottom) hide)
    )
    (pin "1")
    (pin "2")
    (pin "3")
    (instances
      (project "d1600e-psu-breakout-board"
        (path ""
          (reference "D20") (unit 1)
        )
      )
    )
  )

  (symbol (lib_name "TMCS1100A2-Q1_1") (lib_id "antmicroPowerMeasurement:TMCS1100A2-Q1") (at 232.41 49.53 0) (unit 1)
    (in_bom yes) (on_board yes) (dnp no)
    (property "Reference" "U13" (at 241.3 43.18 0)
      (effects (font (size 1.27 1.27)))
    )
    (property "Value" "TMCS1100A2-Q1" (at 265.43 57.15 0)
      (effects (font (size 1.27 1.27) (thickness 0.15)) (justify left bottom) hide)
    )
    (property "Footprint" "antmicro-footprints:SOIC-8_3.9x4.9x1.75mm_P1.27mm" (at 265.43 59.69 0)
      (effects (font (size 1.27 1.27) (thickness 0.15)) (justify left bottom) hide)
    )
    (property "Datasheet" "https://www.ti.com/lit/ds/symlink/tmcs1100-q1.pdf?ts=1647195769204&ref_url=https%253A%252F%252Fwww.mouser.de%252F" (at 265.43 62.23 0)
      (effects (font (size 1.27 1.27) (thickness 0.15)) (justify left bottom) hide)
    )
    (property "MPN" "TMCS1100A2QDRQ1" (at 241.3 45.72 0)
      (effects (font (size 1.27 1.27) (thickness 0.15)))
    )
    (property "Manufacturer" "Texas Instruments" (at 265.43 64.77 0)
      (effects (font (size 1.27 1.27) (thickness 0.15)) (justify left bottom) hide)
    )
    (property "Author" "Antmicro" (at 265.43 67.31 0)
      (effects (font (size 1.27 1.27) (thickness 0.15)) (justify left bottom) hide)
    )
    (property "License" "Apache-2.0" (at 265.43 69.85 0)
      (effects (font (size 1.27 1.27) (thickness 0.15)) (justify left bottom) hide)
    )
    (pin "1")
    (pin "2")
    (pin "3")
    (pin "4")
    (pin "5")
    (pin "6")
    (pin "7")
    (pin "8")
    (instances
      (project "d1600e-psu-breakout-board"
        (path ""
          (reference "U13") (unit 1)
        )
      )
    )
  )

  (symbol (lib_id "antmicropower:GND") (at 104.14 55.88 0) (unit 1)
    (in_bom yes) (on_board yes) (dnp no)
    (property "Reference" "#PWR025" (at 104.14 62.23 0)
      (effects (font (size 1.27 1.27)) hide)
    )
    (property "Value" "GND" (at 104.14 59.69 0)
      (effects (font (size 1.27 1.27) (thickness 0.15)))
    )
    (property "Footprint" "" (at 113.03 63.5 0)
      (effects (font (size 1.27 1.27) (thickness 0.15)) (justify left bottom) hide)
    )
    (property "Datasheet" "" (at 113.03 68.58 0)
      (effects (font (size 1.27 1.27) (thickness 0.15)) (justify left bottom) hide)
    )
    (property "Author" "Antmicro" (at 113.03 63.5 0)
      (effects (font (size 1.27 1.27) (thickness 0.15)) (justify left bottom) hide)
    )
    (property "License" "Apache-2.0" (at 113.03 66.04 0)
      (effects (font (size 1.27 1.27) (thickness 0.15)) (justify left bottom) hide)
    )
    (pin "1")
    (instances
      (project "d1600e-psu-breakout-board"
        (path ""
          (reference "#PWR025") (unit 1)
        )
      )
    )
  )

  (symbol (lib_name "C_100n_0402_1") (lib_id "antmicroCapacitors0402:C_100n_0402") (at 90.17 36.83 0) (mirror x) (unit 1)
    (in_bom yes) (on_board yes) (dnp no)
    (property "Reference" "C30" (at 96.52 35.56 0)
      (effects (font (size 1.27 1.27)))
    )
    (property "Value" "C_100n_0402" (at 110.49 26.67 0)
      (effects (font (size 1.27 1.27) (thickness 0.15)) (justify left bottom) hide)
    )
    (property "Footprint" "antmicro-footprints:C_0402_1005Metric" (at 110.49 24.13 0)
      (effects (font (size 1.27 1.27) (thickness 0.15)) (justify left bottom) hide)
    )
    (property "Datasheet" "https://www.murata.com/products/productdetail?partno=GRM155R61H104KE14%23" (at 110.49 21.59 0)
      (effects (font (size 1.27 1.27) (thickness 0.15)) (justify left bottom) hide)
    )
    (property "Manufacturer" "Murata" (at 110.49 16.51 0)
      (effects (font (size 1.27 1.27) (thickness 0.15)) (justify left bottom) hide)
    )
    (property "MPN" "GRM155R61H104KE14D" (at 110.49 19.05 0)
      (effects (font (size 1.27 1.27) (thickness 0.15)) (justify left bottom) hide)
    )
    (property "Val" "100n" (at 88.9 35.56 0)
      (effects (font (size 1.27 1.27) (thickness 0.15)))
    )
    (property "License" "Apache-2.0" (at 110.49 13.97 0)
      (effects (font (size 1.27 1.27) (thickness 0.15)) (justify left bottom) hide)
    )
    (property "Author" "Antmicro" (at 110.49 11.43 0)
      (effects (font (size 1.27 1.27) (thickness 0.15)) (justify left bottom) hide)
    )
    (property "Voltage" "50V" (at 110.49 8.89 0)
      (effects (font (size 1.27 1.27)) (justify left bottom) hide)
    )
    (property "Dielectric" "X5R" (at 110.49 6.35 0)
      (effects (font (size 1.27 1.27)) (justify left bottom) hide)
    )
    (pin "1")
    (pin "2")
    (instances
      (project "d1600e-psu-breakout-board"
        (path ""
          (reference "C30") (unit 1)
        )
      )
    )
  )

  (symbol (lib_name "C_100n_0402_2") (lib_id "antmicroCapacitors0402:C_100n_0402") (at 312.42 71.12 90) (unit 1)
    (in_bom yes) (on_board yes) (dnp no)
    (property "Reference" "C37" (at 313.055 66.675 90)
      (effects (font (size 1.27 1.27)) (justify right))
    )
    (property "Value" "C_100n_0402" (at 322.58 50.8 0)
      (effects (font (size 1.27 1.27) (thickness 0.15)) (justify left bottom) hide)
    )
    (property "Footprint" "antmicro-footprints:C_0402_1005Metric" (at 325.12 50.8 0)
      (effects (font (size 1.27 1.27) (thickness 0.15)) (justify left bottom) hide)
    )
    (property "Datasheet" "https://www.murata.com/products/productdetail?partno=GRM155R61H104KE14%23" (at 327.66 50.8 0)
      (effects (font (size 1.27 1.27) (thickness 0.15)) (justify left bottom) hide)
    )
    (property "Manufacturer" "Murata" (at 332.74 50.8 0)
      (effects (font (size 1.27 1.27) (thickness 0.15)) (justify left bottom) hide)
    )
    (property "MPN" "GRM155R61H104KE14D" (at 330.2 50.8 0)
      (effects (font (size 1.27 1.27) (thickness 0.15)) (justify left bottom) hide)
    )
    (property "Val" "100n" (at 313.055 69.85 90)
      (effects (font (size 1.27 1.27) (thickness 0.15)) (justify right bottom))
    )
    (property "License" "Apache-2.0" (at 335.28 50.8 0)
      (effects (font (size 1.27 1.27) (thickness 0.15)) (justify left bottom) hide)
    )
    (property "Author" "Antmicro" (at 337.82 50.8 0)
      (effects (font (size 1.27 1.27) (thickness 0.15)) (justify left bottom) hide)
    )
    (property "Voltage" "50V" (at 340.36 50.8 0)
      (effects (font (size 1.27 1.27)) (justify left bottom) hide)
    )
    (property "Dielectric" "X5R" (at 342.9 50.8 0)
      (effects (font (size 1.27 1.27)) (justify left bottom) hide)
    )
    (pin "1")
    (pin "2")
    (instances
      (project "d1600e-psu-breakout-board"
        (path ""
          (reference "C37") (unit 1)
        )
      )
    )
  )

  (sheet (at 190.5 154.94) (size 29.21 16.51) (fields_autoplaced)
    (stroke (width 0.1524) (type solid))
    (fill (color 0 0 0 0.0000))
    (property "Sheetname" "Power switch 1" (at 190.5 154.2284 0)
      (effects (font (size 1.27 1.27)) (justify left bottom))
    )
    (property "Sheetfile" "power-switch.kicad_sch" (at 190.5 172.0346 0)
      (effects (font (size 1.27 1.27)) (justify left top))
    )
    (pin "VCC3V3" input (at 190.5 162.56 180)
      (effects (font (size 1.27 1.27)) (justify left))
    )
    (pin "SW_ON" input (at 190.5 167.64 180)
      (effects (font (size 1.27 1.27)) (justify left))
    )
    (pin "VIN12V" input (at 190.5 158.75 180)
      (effects (font (size 1.27 1.27)) (justify left))
    )
    (pin "VOUT" output (at 219.71 158.75 0)
      (effects (font (size 1.27 1.27)) (justify right))
    )
    (instances
      (project "d1600e-psu-breakout-board"
        (path "" (page "5"))
      )
    )
  )

  (sheet (at 190.5 177.8) (size 29.21 15.24) (fields_autoplaced)
    (stroke (width 0.1524) (type solid))
    (fill (color 0 0 0 0.0000))
    (property "Sheetname" "Power switch 2" (at 190.5 177.0884 0)
      (effects (font (size 1.27 1.27)) (justify left bottom))
    )
    (property "Sheetfile" "power-switch.kicad_sch" (at 190.5 193.6246 0)
      (effects (font (size 1.27 1.27)) (justify left top))
    )
    (pin "VCC3V3" input (at 190.5 185.42 180)
      (effects (font (size 1.27 1.27)) (justify left))
    )
    (pin "SW_ON" input (at 190.5 190.5 180)
      (effects (font (size 1.27 1.27)) (justify left))
    )
    (pin "VIN12V" input (at 190.5 181.61 180)
      (effects (font (size 1.27 1.27)) (justify left))
    )
    (pin "VOUT" output (at 219.71 181.61 0)
      (effects (font (size 1.27 1.27)) (justify right))
    )
    (instances
      (project "d1600e-psu-breakout-board"
        (path "" (page "6"))
      )
    )
  )

  (sheet (at 190.5 242.57) (size 29.21 15.24) (fields_autoplaced)
    (stroke (width 0.1524) (type solid))
    (fill (color 0 0 0 0.0000))
    (property "Sheetname" "Power switch 5" (at 190.5 241.8584 0)
      (effects (font (size 1.27 1.27)) (justify left bottom))
    )
    (property "Sheetfile" "power-switch.kicad_sch" (at 190.5 258.3946 0)
      (effects (font (size 1.27 1.27)) (justify left top))
    )
    (pin "VCC3V3" input (at 190.5 250.19 180)
      (effects (font (size 1.27 1.27)) (justify left))
    )
    (pin "SW_ON" input (at 190.5 255.27 180)
      (effects (font (size 1.27 1.27)) (justify left))
    )
    (pin "VIN12V" input (at 190.5 246.38 180)
      (effects (font (size 1.27 1.27)) (justify left))
    )
    (pin "VOUT" output (at 219.71 246.38 0)
      (effects (font (size 1.27 1.27)) (justify right))
    )
    (instances
      (project "d1600e-psu-breakout-board"
        (path "" (page "9"))
      )
    )
  )

  (sheet (at 190.5 199.39) (size 29.21 15.24) (fields_autoplaced)
    (stroke (width 0.1524) (type solid))
    (fill (color 0 0 0 0.0000))
    (property "Sheetname" "Power switch 3" (at 190.5 198.6784 0)
      (effects (font (size 1.27 1.27)) (justify left bottom))
    )
    (property "Sheetfile" "power-switch.kicad_sch" (at 190.5 215.2146 0)
      (effects (font (size 1.27 1.27)) (justify left top))
    )
    (pin "VCC3V3" input (at 190.5 207.01 180)
      (effects (font (size 1.27 1.27)) (justify left))
    )
    (pin "SW_ON" input (at 190.5 212.09 180)
      (effects (font (size 1.27 1.27)) (justify left))
    )
    (pin "VIN12V" input (at 190.5 203.2 180)
      (effects (font (size 1.27 1.27)) (justify left))
    )
    (pin "VOUT" output (at 219.71 203.2 0)
      (effects (font (size 1.27 1.27)) (justify right))
    )
    (instances
      (project "d1600e-psu-breakout-board"
        (path "" (page "7"))
      )
    )
  )

  (sheet (at 190.5 220.98) (size 29.21 15.24) (fields_autoplaced)
    (stroke (width 0.1524) (type solid))
    (fill (color 0 0 0 0.0000))
    (property "Sheetname" "Power switch 4" (at 190.5 220.2684 0)
      (effects (font (size 1.27 1.27)) (justify left bottom))
    )
    (property "Sheetfile" "power-switch.kicad_sch" (at 190.5 236.8046 0)
      (effects (font (size 1.27 1.27)) (justify left top))
    )
    (pin "VCC3V3" input (at 190.5 228.6 180)
      (effects (font (size 1.27 1.27)) (justify left))
    )
    (pin "SW_ON" input (at 190.5 233.68 180)
      (effects (font (size 1.27 1.27)) (justify left))
    )
    (pin "VIN12V" input (at 190.5 224.79 180)
      (effects (font (size 1.27 1.27)) (justify left))
    )
    (pin "VOUT" output (at 219.71 224.79 0)
      (effects (font (size 1.27 1.27)) (justify right))
    )
    (instances
      (project "d1600e-psu-breakout-board"
        (path "" (page "8"))
      )
    )
  )
)
